(kicad_sch
	(version 20250114)
	(generator "eeschema")
	(generator_version "9.0")
	(paper "A3")
	(title_block
		(title "Antmicro Baseboard for Jetson AGX Thor")
		(date "2026-02-17")
		(rev "1.1.0")
		(company "Antmicro Ltd")
		(comment 1 "www.antmicro.com")
	)
	(bus_alias "CAM_CTRL"
		(members "CSIA_PEN" "CSIB_PEN" "CSIA_FLG" "CSIB_FLG" "VSYNC_CAM0" "VSYNC_CAM1"
			"VSYNC_CAM2" "VSYNC_CAM3"
		)
	)
	(bus_alias "M2_E"
		(members "W_DIS_1" "W_DIS_2" "~{UART_WAKE}" "VENDOR")
	)
	(text "NOTE:\nDo not use as GPIO\n(strap pins on SOM):\nGPIO42\nGPIO38\nGPIO37\nGPIO17\n"
		(exclude_from_sim no)
		(at 243.84 33.02 0)
		(effects
			(font
				(size 1.27 1.27)
			)
			(justify left)
		)
	)
	(text "All I2C are \nOpen-Drain 1.8V"
		(exclude_from_sim no)
		(at 386.08 25.4 0)
		(effects
			(font
				(size 1.27 1.27)
			)
			(justify left)
		)
	)
	(text "All UART are \nCMOS - 1.8V"
		(exclude_from_sim no)
		(at 386.08 16.51 0)
		(effects
			(font
				(size 1.27 1.27)
			)
			(justify left)
		)
	)
	(text "All CAN pins are \nCMOS - 3V3"
		(exclude_from_sim no)
		(at 386.08 21.59 0)
		(effects
			(font
				(size 1.27 1.27)
			)
			(justify left)
		)
	)
	(text "Level shifters"
		(exclude_from_sim no)
		(at 83.566 26.416 0)
		(effects
			(font
				(size 2.54 2.54)
				(thickness 0.508)
				(bold yes)
			)
			(justify left bottom)
		)
	)
	(text "GPIO"
		(exclude_from_sim no)
		(at 223.52 19.05 0)
		(effects
			(font
				(size 2.54 2.54)
				(thickness 0.508)
				(bold yes)
			)
			(justify left bottom)
		)
	)
	(text "UART/I2C/SPI/CAN/FAN"
		(exclude_from_sim no)
		(at 317.5 19.05 0)
		(effects
			(font
				(size 2.54 2.54)
				(thickness 0.508)
				(bold yes)
			)
			(justify left bottom)
		)
	)
	(junction
		(at 106.68 248.92)
		(diameter 0)
		(color 0 0 0 0)
	)
	(junction
		(at 52.07 97.79)
		(diameter 0)
		(color 0 0 0 0)
	)
	(junction
		(at 77.47 139.7)
		(diameter 0)
		(color 0 0 0 0)
	)
	(junction
		(at 52.07 113.03)
		(diameter 0)
		(color 0 0 0 0)
	)
	(junction
		(at 52.07 62.23)
		(diameter 0)
		(color 0 0 0 0)
	)
	(junction
		(at 125.73 97.79)
		(diameter 0)
		(color 0 0 0 0)
	)
	(junction
		(at 62.23 97.79)
		(diameter 0)
		(color 0 0 0 0)
	)
	(junction
		(at 125.73 115.57)
		(diameter 0)
		(color 0 0 0 0)
	)
	(junction
		(at 62.23 64.77)
		(diameter 0)
		(color 0 0 0 0)
	)
	(junction
		(at 125.73 64.77)
		(diameter 0)
		(color 0 0 0 0)
	)
	(junction
		(at 72.39 118.11)
		(diameter 0)
		(color 0 0 0 0)
	)
	(junction
		(at 41.91 110.49)
		(diameter 0)
		(color 0 0 0 0)
	)
	(junction
		(at 80.01 246.38)
		(diameter 0)
		(color 0 0 0 0)
	)
	(junction
		(at 83.82 241.3)
		(diameter 0)
		(color 0 0 0 0)
	)
	(junction
		(at 83.82 105.41)
		(diameter 0)
		(color 0 0 0 0)
	)
	(junction
		(at 115.57 118.11)
		(diameter 0)
		(color 0 0 0 0)
	)
	(junction
		(at 72.39 67.31)
		(diameter 0)
		(color 0 0 0 0)
	)
	(junction
		(at 62.23 46.99)
		(diameter 0)
		(color 0 0 0 0)
	)
	(junction
		(at 135.89 46.99)
		(diameter 0)
		(color 0 0 0 0)
	)
	(junction
		(at 135.89 62.23)
		(diameter 0)
		(color 0 0 0 0)
	)
	(junction
		(at 80.01 182.88)
		(diameter 0)
		(color 0 0 0 0)
	)
	(junction
		(at 130.81 97.79)
		(diameter 0)
		(color 0 0 0 0)
	)
	(junction
		(at 57.15 97.79)
		(diameter 0)
		(color 0 0 0 0)
	)
	(junction
		(at 135.89 113.03)
		(diameter 0)
		(color 0 0 0 0)
	)
	(junction
		(at 83.82 54.61)
		(diameter 0)
		(color 0 0 0 0)
	)
	(junction
		(at 135.89 97.79)
		(diameter 0)
		(color 0 0 0 0)
	)
	(junction
		(at 146.05 110.49)
		(diameter 0)
		(color 0 0 0 0)
	)
	(junction
		(at 62.23 115.57)
		(diameter 0)
		(color 0 0 0 0)
	)
	(junction
		(at 41.91 59.69)
		(diameter 0)
		(color 0 0 0 0)
	)
	(junction
		(at 146.05 59.69)
		(diameter 0)
		(color 0 0 0 0)
	)
	(junction
		(at 113.03 203.2)
		(diameter 0)
		(color 0 0 0 0)
	)
	(junction
		(at 113.03 139.7)
		(diameter 0)
		(color 0 0 0 0)
	)
	(junction
		(at 52.07 46.99)
		(diameter 0)
		(color 0 0 0 0)
	)
	(junction
		(at 125.73 46.99)
		(diameter 0)
		(color 0 0 0 0)
	)
	(junction
		(at 130.81 46.99)
		(diameter 0)
		(color 0 0 0 0)
	)
	(junction
		(at 115.57 67.31)
		(diameter 0)
		(color 0 0 0 0)
	)
	(junction
		(at 77.47 203.2)
		(diameter 0)
		(color 0 0 0 0)
	)
	(junction
		(at 57.15 46.99)
		(diameter 0)
		(color 0 0 0 0)
	)
	(junction
		(at 83.82 177.8)
		(diameter 0)
		(color 0 0 0 0)
	)
	(no_connect
		(at 318.77 82.55)
	)
	(no_connect
		(at 318.77 95.25)
	)
	(no_connect
		(at 361.95 193.04)
	)
	(no_connect
		(at 240.03 35.56)
	)
	(no_connect
		(at 363.22 95.25)
	)
	(no_connect
		(at 363.22 97.79)
	)
	(no_connect
		(at 318.77 133.35)
	)
	(no_connect
		(at 363.22 231.14)
	)
	(no_connect
		(at 363.22 236.22)
	)
	(no_connect
		(at 363.22 227.33)
	)
	(no_connect
		(at 240.03 76.2)
	)
	(no_connect
		(at 361.95 171.45)
	)
	(no_connect
		(at 363.22 233.68)
	)
	(no_connect
		(at 318.77 97.79)
	)
	(no_connect
		(at 361.95 184.15)
	)
	(no_connect
		(at 240.03 38.1)
	)
	(no_connect
		(at 361.95 180.34)
	)
	(no_connect
		(at 363.22 90.17)
	)
	(no_connect
		(at 363.22 219.71)
	)
	(no_connect
		(at 318.77 120.65)
	)
	(no_connect
		(at 318.77 130.81)
	)
	(no_connect
		(at 363.22 210.82)
	)
	(no_connect
		(at 105.41 160.02)
	)
	(no_connect
		(at 318.77 85.09)
	)
	(no_connect
		(at 363.22 114.3)
	)
	(no_connect
		(at 363.22 92.71)
	)
	(no_connect
		(at 363.22 215.9)
	)
	(no_connect
		(at 361.95 177.8)
	)
	(no_connect
		(at 363.22 222.25)
	)
	(no_connect
		(at 318.77 123.19)
	)
	(no_connect
		(at 318.77 115.57)
	)
	(no_connect
		(at 318.77 88.9)
	)
	(no_connect
		(at 363.22 208.28)
	)
	(no_connect
		(at 318.77 102.87)
	)
	(no_connect
		(at 363.22 224.79)
	)
	(no_connect
		(at 318.77 74.93)
	)
	(no_connect
		(at 361.95 190.5)
	)
	(no_connect
		(at 214.63 58.42)
	)
	(no_connect
		(at 240.03 40.64)
	)
	(no_connect
		(at 318.77 110.49)
	)
	(no_connect
		(at 361.95 152.4)
	)
	(no_connect
		(at 318.77 128.27)
	)
	(no_connect
		(at 318.77 91.44)
	)
	(no_connect
		(at 105.41 218.44)
	)
	(no_connect
		(at 361.95 173.99)
	)
	(no_connect
		(at 240.03 43.18)
	)
	(no_connect
		(at 85.09 236.22)
	)
	(no_connect
		(at 318.77 113.03)
	)
	(no_connect
		(at 363.22 213.36)
	)
	(no_connect
		(at 361.95 154.94)
	)
	(no_connect
		(at 361.95 186.69)
	)
	(no_connect
		(at 318.77 105.41)
	)
	(no_connect
		(at 318.77 118.11)
	)
	(no_connect
		(at 318.77 77.47)
	)
	(no_connect
		(at 318.77 135.89)
	)
	(no_connect
		(at 363.22 238.76)
	)
	(bus_entry
		(at 378.46 161.29)
		(size 1.27 -1.27)
		(stroke
			(width 0)
			(type default)
		)
	)
	(bus_entry
		(at 382.27 41.91)
		(size -1.27 1.27)
		(stroke
			(width 0)
			(type default)
		)
	)
	(bus_entry
		(at 379.73 243.84)
		(size -1.27 1.27)
		(stroke
			(width 0)
			(type default)
		)
	)
	(bus_entry
		(at 300.99 224.79)
		(size 1.27 1.27)
		(stroke
			(width 0)
			(type default)
		)
	)
	(bus_entry
		(at 166.37 63.5)
		(size -1.27 1.27)
		(stroke
			(width 0)
			(type default)
		)
	)
	(bus_entry
		(at 304.8 180.34)
		(size -1.27 -1.27)
		(stroke
			(width 0)
			(type default)
		)
	)
	(bus_entry
		(at 300.99 238.76)
		(size 1.27 1.27)
		(stroke
			(width 0)
			(type default)
		)
	)
	(bus_entry
		(at 190.5 39.37)
		(size 1.27 1.27)
		(stroke
			(width 0)
			(type default)
		)
	)
	(bus_entry
		(at 262.89 62.23)
		(size -1.27 1.27)
		(stroke
			(width 0)
			(type default)
		)
	)
	(bus_entry
		(at 300.99 236.22)
		(size 1.27 1.27)
		(stroke
			(width 0)
			(type default)
		)
	)
	(bus_entry
		(at 382.27 48.26)
		(size -1.27 1.27)
		(stroke
			(width 0)
			(type default)
		)
	)
	(bus_entry
		(at 129.54 219.71)
		(size -1.27 1.27)
		(stroke
			(width 0)
			(type default)
		)
	)
	(bus_entry
		(at 165.1 115.57)
		(size 1.27 -1.27)
		(stroke
			(width 0)
			(type default)
		)
	)
	(bus_entry
		(at 377.19 107.95)
		(size -1.27 1.27)
		(stroke
			(width 0)
			(type default)
		)
	)
	(bus_entry
		(at 304.8 177.8)
		(size -1.27 -1.27)
		(stroke
			(width 0)
			(type default)
		)
	)
	(bus_entry
		(at 269.24 52.07)
		(size -1.27 1.27)
		(stroke
			(width 0)
			(type default)
		)
	)
	(bus_entry
		(at 262.89 67.31)
		(size -1.27 1.27)
		(stroke
			(width 0)
			(type default)
		)
	)
	(bus_entry
		(at 382.27 78.74)
		(size -1.27 1.27)
		(stroke
			(width 0)
			(type default)
		)
	)
	(bus_entry
		(at 382.27 35.56)
		(size -1.27 1.27)
		(stroke
			(width 0)
			(type default)
		)
	)
	(bus_entry
		(at 165.1 113.03)
		(size 1.27 -1.27)
		(stroke
			(width 0)
			(type default)
		)
	)
	(bus_entry
		(at 166.37 66.04)
		(size -1.27 1.27)
		(stroke
			(width 0)
			(type default)
		)
	)
	(bus_entry
		(at 382.27 73.66)
		(size -1.27 1.27)
		(stroke
			(width 0)
			(type default)
		)
	)
	(bus_entry
		(at 382.27 71.12)
		(size -1.27 1.27)
		(stroke
			(width 0)
			(type default)
		)
	)
	(bus_entry
		(at 304.8 35.56)
		(size 1.27 1.27)
		(stroke
			(width 0)
			(type default)
		)
	)
	(bus_entry
		(at 382.27 76.2)
		(size -1.27 1.27)
		(stroke
			(width 0)
			(type default)
		)
	)
	(bus_entry
		(at 262.89 59.69)
		(size -1.27 1.27)
		(stroke
			(width 0)
			(type default)
		)
	)
	(bus_entry
		(at 304.8 33.02)
		(size 1.27 1.27)
		(stroke
			(width 0)
			(type default)
		)
	)
	(bus_entry
		(at 377.19 105.41)
		(size -1.27 1.27)
		(stroke
			(width 0)
			(type default)
		)
	)
	(bus_entry
		(at 269.24 49.53)
		(size -1.27 1.27)
		(stroke
			(width 0)
			(type default)
		)
	)
	(bus_entry
		(at 165.1 118.11)
		(size 1.27 -1.27)
		(stroke
			(width 0)
			(type default)
		)
	)
	(bus_entry
		(at 300.99 229.87)
		(size 1.27 1.27)
		(stroke
			(width 0)
			(type default)
		)
	)
	(bus_entry
		(at 304.8 38.1)
		(size 1.27 1.27)
		(stroke
			(width 0)
			(type default)
		)
	)
	(bus_entry
		(at 304.8 46.99)
		(size 1.27 1.27)
		(stroke
			(width 0)
			(type default)
		)
	)
	(bus_entry
		(at 300.99 241.3)
		(size 1.27 1.27)
		(stroke
			(width 0)
			(type default)
		)
	)
	(bus_entry
		(at 129.54 227.33)
		(size -1.27 1.27)
		(stroke
			(width 0)
			(type default)
		)
	)
	(bus_entry
		(at 190.5 41.91)
		(size 1.27 1.27)
		(stroke
			(width 0)
			(type default)
		)
	)
	(bus_entry
		(at 382.27 33.02)
		(size -1.27 1.27)
		(stroke
			(width 0)
			(type default)
		)
	)
	(bus_entry
		(at 129.54 222.25)
		(size -1.27 1.27)
		(stroke
			(width 0)
			(type default)
		)
	)
	(bus_entry
		(at 377.19 102.87)
		(size -1.27 1.27)
		(stroke
			(width 0)
			(type default)
		)
	)
	(bus_entry
		(at 300.99 222.25)
		(size 1.27 1.27)
		(stroke
			(width 0)
			(type default)
		)
	)
	(bus_entry
		(at 165.1 110.49)
		(size 1.27 -1.27)
		(stroke
			(width 0)
			(type default)
		)
	)
	(bus_entry
		(at 304.8 58.42)
		(size 1.27 1.27)
		(stroke
			(width 0)
			(type default)
		)
	)
	(bus_entry
		(at 379.73 166.37)
		(size -1.27 1.27)
		(stroke
			(width 0)
			(type default)
		)
	)
	(bus_entry
		(at 269.24 46.99)
		(size -1.27 1.27)
		(stroke
			(width 0)
			(type default)
		)
	)
	(bus_entry
		(at 304.8 66.04)
		(size 1.27 1.27)
		(stroke
			(width 0)
			(type default)
		)
	)
	(bus_entry
		(at 304.8 68.58)
		(size 1.27 1.27)
		(stroke
			(width 0)
			(type default)
		)
	)
	(bus_entry
		(at 379.73 163.83)
		(size -1.27 1.27)
		(stroke
			(width 0)
			(type default)
		)
	)
	(bus_entry
		(at 377.19 100.33)
		(size -1.27 1.27)
		(stroke
			(width 0)
			(type default)
		)
	)
	(bus_entry
		(at 304.8 43.18)
		(size 1.27 1.27)
		(stroke
			(width 0)
			(type default)
		)
	)
	(bus_entry
		(at 304.8 49.53)
		(size 1.27 1.27)
		(stroke
			(width 0)
			(type default)
		)
	)
	(bus_entry
		(at 262.89 64.77)
		(size -1.27 1.27)
		(stroke
			(width 0)
			(type default)
		)
	)
	(bus_entry
		(at 382.27 54.61)
		(size -1.27 1.27)
		(stroke
			(width 0)
			(type default)
		)
	)
	(bus_entry
		(at 190.5 44.45)
		(size 1.27 1.27)
		(stroke
			(width 0)
			(type default)
		)
	)
	(bus_entry
		(at 129.54 224.79)
		(size -1.27 1.27)
		(stroke
			(width 0)
			(type default)
		)
	)
	(bus_entry
		(at 166.37 60.96)
		(size -1.27 1.27)
		(stroke
			(width 0)
			(type default)
		)
	)
	(bus_entry
		(at 300.99 227.33)
		(size 1.27 1.27)
		(stroke
			(width 0)
			(type default)
		)
	)
	(bus_entry
		(at 190.5 46.99)
		(size 1.27 1.27)
		(stroke
			(width 0)
			(type default)
		)
	)
	(bus_entry
		(at 378.46 158.75)
		(size 1.27 -1.27)
		(stroke
			(width 0)
			(type default)
		)
	)
	(bus_entry
		(at 166.37 58.42)
		(size -1.27 1.27)
		(stroke
			(width 0)
			(type default)
		)
	)
	(bus_entry
		(at 382.27 52.07)
		(size -1.27 1.27)
		(stroke
			(width 0)
			(type default)
		)
	)
	(bus_entry
		(at 382.27 45.72)
		(size -1.27 1.27)
		(stroke
			(width 0)
			(type default)
		)
	)
	(bus_entry
		(at 379.73 241.3)
		(size -1.27 1.27)
		(stroke
			(width 0)
			(type default)
		)
	)
	(bus_entry
		(at 300.99 233.68)
		(size 1.27 1.27)
		(stroke
			(width 0)
			(type default)
		)
	)
	(bus_entry
		(at 300.99 207.01)
		(size 1.27 1.27)
		(stroke
			(width 0)
			(type default)
		)
	)
	(bus_entry
		(at 382.27 39.37)
		(size -1.27 1.27)
		(stroke
			(width 0)
			(type default)
		)
	)
	(bus_entry
		(at 304.8 52.07)
		(size 1.27 1.27)
		(stroke
			(width 0)
			(type default)
		)
	)
	(bus_entry
		(at 304.8 54.61)
		(size 1.27 1.27)
		(stroke
			(width 0)
			(type default)
		)
	)
	(bus_entry
		(at 304.8 63.5)
		(size 1.27 1.27)
		(stroke
			(width 0)
			(type default)
		)
	)
	(bus_entry
		(at 269.24 54.61)
		(size -1.27 1.27)
		(stroke
			(width 0)
			(type default)
		)
	)
	(bus_entry
		(at 304.8 40.64)
		(size 1.27 1.27)
		(stroke
			(width 0)
			(type default)
		)
	)
	(bus_entry
		(at 304.8 60.96)
		(size 1.27 1.27)
		(stroke
			(width 0)
			(type default)
		)
	)
	(polyline
		(pts
			(xy 92.71 173.99) (xy 92.71 172.72)
		)
		(stroke
			(width 0)
			(type default)
		)
	)
	(wire
		(pts
			(xy 365.76 135.89) (xy 363.22 135.89)
		)
		(stroke
			(width 0)
			(type default)
		)
	)
	(wire
		(pts
			(xy 304.8 173.99) (xy 321.31 173.99)
		)
		(stroke
			(width 0)
			(type default)
		)
	)
	(wire
		(pts
			(xy 83.82 69.85) (xy 83.82 71.12)
		)
		(stroke
			(width 0)
			(type default)
		)
	)
	(wire
		(pts
			(xy 306.07 44.45) (xy 318.77 44.45)
		)
		(stroke
			(width 0)
			(type default)
		)
	)
	(wire
		(pts
			(xy 83.82 241.3) (xy 83.82 250.19)
		)
		(stroke
			(width 0)
			(type default)
		)
	)
	(bus
		(pts
			(xy 382.27 52.07) (xy 382.27 54.61)
		)
		(stroke
			(width 0)
			(type default)
		)
	)
	(wire
		(pts
			(xy 381 43.18) (xy 363.22 43.18)
		)
		(stroke
			(width 0)
			(type default)
		)
	)
	(bus
		(pts
			(xy 300.99 236.22) (xy 300.99 238.76)
		)
		(stroke
			(width 0)
			(type default)
		)
	)
	(polyline
		(pts
			(xy 91.44 228.6) (xy 92.71 229.87)
		)
		(stroke
			(width 0)
			(type default)
		)
	)
	(wire
		(pts
			(xy 125.73 115.57) (xy 165.1 115.57)
		)
		(stroke
			(width 0)
			(type default)
		)
	)
	(bus
		(pts
			(xy 167.64 57.15) (xy 166.37 58.42)
		)
		(stroke
			(width 0)
			(type default)
		)
	)
	(polyline
		(pts
			(xy 97.79 224.79) (xy 99.06 223.52)
		)
		(stroke
			(width 0)
			(type default)
		)
	)
	(wire
		(pts
			(xy 105.41 113.03) (xy 135.89 113.03)
		)
		(stroke
			(width 0)
			(type default)
		)
	)
	(polyline
		(pts
			(xy 92.71 234.95) (xy 92.71 233.68)
		)
		(stroke
			(width 0)
			(type default)
		)
	)
	(polyline
		(pts
			(xy 92.71 167.64) (xy 92.71 166.37)
		)
		(stroke
			(width 0)
			(type default)
		)
	)
	(wire
		(pts
			(xy 115.57 118.11) (xy 165.1 118.11)
		)
		(stroke
			(width 0)
			(type default)
		)
	)
	(wire
		(pts
			(xy 85.09 220.98) (xy 59.69 220.98)
		)
		(stroke
			(width 0)
			(type default)
		)
	)
	(wire
		(pts
			(xy 62.23 115.57) (xy 85.09 115.57)
		)
		(stroke
			(width 0)
			(type default)
		)
	)
	(wire
		(pts
			(xy 240.03 45.72) (xy 262.89 45.72)
		)
		(stroke
			(width 0)
			(type default)
		)
	)
	(polyline
		(pts
			(xy 99.06 218.44) (xy 97.79 217.17)
		)
		(stroke
			(width 0)
			(type default)
		)
	)
	(polyline
		(pts
			(xy 99.06 157.48) (xy 97.79 156.21)
		)
		(stroke
			(width 0)
			(type default)
		)
	)
	(wire
		(pts
			(xy 135.89 62.23) (xy 165.1 62.23)
		)
		(stroke
			(width 0)
			(type default)
		)
	)
	(bus
		(pts
			(xy 297.18 220.98) (xy 299.72 220.98)
		)
		(stroke
			(width 0)
			(type default)
		)
	)
	(wire
		(pts
			(xy 304.8 158.75) (xy 321.31 158.75)
		)
		(stroke
			(width 0)
			(type default)
		)
	)
	(bus
		(pts
			(xy 377.19 100.33) (xy 377.19 102.87)
		)
		(stroke
			(width 0)
			(type default)
		)
	)
	(wire
		(pts
			(xy 106.68 121.92) (xy 106.68 120.65)
		)
		(stroke
			(width 0)
			(type default)
		)
	)
	(wire
		(pts
			(xy 106.68 104.14) (xy 106.68 105.41)
		)
		(stroke
			(width 0)
			(type default)
		)
	)
	(polyline
		(pts
			(xy 99.06 172.72) (xy 92.71 172.72)
		)
		(stroke
			(width 0)
			(type default)
		)
	)
	(wire
		(pts
			(xy 106.68 69.85) (xy 105.41 69.85)
		)
		(stroke
			(width 0)
			(type default)
		)
	)
	(wire
		(pts
			(xy 193.04 76.2) (xy 214.63 76.2)
		)
		(stroke
			(width 0)
			(type default)
		)
	)
	(wire
		(pts
			(xy 90.17 34.29) (xy 90.17 35.56)
		)
		(stroke
			(width 0)
			(type default)
		)
	)
	(wire
		(pts
			(xy 57.15 97.79) (xy 62.23 97.79)
		)
		(stroke
			(width 0)
			(type default)
		)
	)
	(wire
		(pts
			(xy 83.82 241.3) (xy 85.09 241.3)
		)
		(stroke
			(width 0)
			(type default)
		)
	)
	(wire
		(pts
			(xy 146.05 59.69) (xy 165.1 59.69)
		)
		(stroke
			(width 0)
			(type default)
		)
	)
	(wire
		(pts
			(xy 363.22 72.39) (xy 381 72.39)
		)
		(stroke
			(width 0)
			(type default)
		)
	)
	(wire
		(pts
			(xy 77.47 203.2) (xy 77.47 204.47)
		)
		(stroke
			(width 0)
			(type default)
		)
	)
	(polyline
		(pts
			(xy 99.06 160.02) (xy 97.79 158.75)
		)
		(stroke
			(width 0)
			(type default)
		)
	)
	(bus
		(pts
			(xy 304.8 63.5) (xy 304.8 66.04)
		)
		(stroke
			(width 0)
			(type default)
		)
	)
	(wire
		(pts
			(xy 307.34 217.17) (xy 320.04 217.17)
		)
		(stroke
			(width 0)
			(type default)
		)
	)
	(wire
		(pts
			(xy 77.47 209.55) (xy 77.47 210.82)
		)
		(stroke
			(width 0)
			(type default)
		)
	)
	(wire
		(pts
			(xy 113.03 146.05) (xy 113.03 147.32)
		)
		(stroke
			(width 0)
			(type default)
		)
	)
	(bus
		(pts
			(xy 133.35 218.44) (xy 130.81 218.44)
		)
		(stroke
			(width 0)
			(type default)
		)
	)
	(wire
		(pts
			(xy 77.47 139.7) (xy 77.47 140.97)
		)
		(stroke
			(width 0)
			(type default)
		)
	)
	(wire
		(pts
			(xy 302.26 240.03) (xy 320.04 240.03)
		)
		(stroke
			(width 0)
			(type default)
		)
	)
	(wire
		(pts
			(xy 80.01 182.88) (xy 85.09 182.88)
		)
		(stroke
			(width 0)
			(type default)
		)
	)
	(wire
		(pts
			(xy 115.57 49.53) (xy 115.57 46.99)
		)
		(stroke
			(width 0)
			(type default)
		)
	)
	(wire
		(pts
			(xy 52.07 55.88) (xy 52.07 62.23)
		)
		(stroke
			(width 0)
			(type default)
		)
	)
	(wire
		(pts
			(xy 59.69 226.06) (xy 85.09 226.06)
		)
		(stroke
			(width 0)
			(type default)
		)
	)
	(bus
		(pts
			(xy 386.08 38.1) (xy 383.54 38.1)
		)
		(stroke
			(width 0)
			(type default)
		)
	)
	(wire
		(pts
			(xy 107.95 203.2) (xy 113.03 203.2)
		)
		(stroke
			(width 0)
			(type default)
		)
	)
	(bus
		(pts
			(xy 270.51 45.72) (xy 269.24 46.99)
		)
		(stroke
			(width 0)
			(type default)
		)
	)
	(wire
		(pts
			(xy 41.91 101.6) (xy 41.91 97.79)
		)
		(stroke
			(width 0)
			(type default)
		)
	)
	(wire
		(pts
			(xy 111.76 167.64) (xy 105.41 167.64)
		)
		(stroke
			(width 0)
			(type default)
		)
	)
	(bus
		(pts
			(xy 304.8 66.04) (xy 304.8 68.58)
		)
		(stroke
			(width 0)
			(type default)
		)
	)
	(wire
		(pts
			(xy 363.22 109.22) (xy 375.92 109.22)
		)
		(stroke
			(width 0)
			(type default)
		)
	)
	(wire
		(pts
			(xy 116.84 233.68) (xy 105.41 233.68)
		)
		(stroke
			(width 0)
			(type default)
		)
	)
	(wire
		(pts
			(xy 311.15 247.65) (xy 318.77 247.65)
		)
		(stroke
			(width 0)
			(type default)
		)
	)
	(wire
		(pts
			(xy 304.8 171.45) (xy 321.31 171.45)
		)
		(stroke
			(width 0)
			(type default)
		)
	)
	(wire
		(pts
			(xy 106.68 71.12) (xy 106.68 69.85)
		)
		(stroke
			(width 0)
			(type default)
		)
	)
	(bus
		(pts
			(xy 168.91 107.95) (xy 167.64 107.95)
		)
		(stroke
			(width 0)
			(type default)
		)
	)
	(wire
		(pts
			(xy 106.68 248.92) (xy 106.68 250.19)
		)
		(stroke
			(width 0)
			(type default)
		)
	)
	(polyline
		(pts
			(xy 99.06 223.52) (xy 97.79 222.25)
		)
		(stroke
			(width 0)
			(type default)
		)
	)
	(wire
		(pts
			(xy 83.82 57.15) (xy 85.09 57.15)
		)
		(stroke
			(width 0)
			(type default)
		)
	)
	(wire
		(pts
			(xy 90.17 85.09) (xy 90.17 86.36)
		)
		(stroke
			(width 0)
			(type default)
		)
	)
	(wire
		(pts
			(xy 27.94 62.23) (xy 52.07 62.23)
		)
		(stroke
			(width 0)
			(type default)
		)
	)
	(bus
		(pts
			(xy 304.8 33.02) (xy 304.8 35.56)
		)
		(stroke
			(width 0)
			(type default)
		)
	)
	(bus
		(pts
			(xy 304.8 52.07) (xy 304.8 54.61)
		)
		(stroke
			(width 0)
			(type default)
		)
	)
	(bus
		(pts
			(xy 304.8 38.1) (xy 304.8 40.64)
		)
		(stroke
			(width 0)
			(type default)
		)
	)
	(wire
		(pts
			(xy 85.09 223.52) (xy 59.69 223.52)
		)
		(stroke
			(width 0)
			(type default)
		)
	)
	(wire
		(pts
			(xy 146.05 105.41) (xy 146.05 110.49)
		)
		(stroke
			(width 0)
			(type default)
		)
	)
	(wire
		(pts
			(xy 302.26 228.6) (xy 320.04 228.6)
		)
		(stroke
			(width 0)
			(type default)
		)
	)
	(bus
		(pts
			(xy 383.54 240.03) (xy 381 240.03)
		)
		(stroke
			(width 0)
			(type default)
		)
	)
	(wire
		(pts
			(xy 105.41 213.36) (xy 107.95 213.36)
		)
		(stroke
			(width 0)
			(type default)
		)
	)
	(wire
		(pts
			(xy 130.81 44.45) (xy 130.81 46.99)
		)
		(stroke
			(width 0)
			(type default)
		)
	)
	(polyline
		(pts
			(xy 92.71 171.45) (xy 92.71 170.18)
		)
		(stroke
			(width 0)
			(type default)
		)
	)
	(wire
		(pts
			(xy 106.68 185.42) (xy 106.68 186.69)
		)
		(stroke
			(width 0)
			(type default)
		)
	)
	(wire
		(pts
			(xy 41.91 46.99) (xy 52.07 46.99)
		)
		(stroke
			(width 0)
			(type default)
		)
	)
	(polyline
		(pts
			(xy 92.71 236.22) (xy 92.71 234.95)
		)
		(stroke
			(width 0)
			(type default)
		)
	)
	(wire
		(pts
			(xy 302.26 226.06) (xy 320.04 226.06)
		)
		(stroke
			(width 0)
			(type default)
		)
	)
	(wire
		(pts
			(xy 41.91 110.49) (xy 85.09 110.49)
		)
		(stroke
			(width 0)
			(type default)
		)
	)
	(polyline
		(pts
			(xy 91.44 162.56) (xy 97.79 162.56)
		)
		(stroke
			(width 0)
			(type default)
		)
	)
	(bus
		(pts
			(xy 186.69 38.1) (xy 189.23 38.1)
		)
		(stroke
			(width 0)
			(type default)
		)
	)
	(wire
		(pts
			(xy 363.22 242.57) (xy 378.46 242.57)
		)
		(stroke
			(width 0)
			(type default)
		)
	)
	(wire
		(pts
			(xy 83.82 104.14) (xy 83.82 105.41)
		)
		(stroke
			(width 0)
			(type default)
		)
	)
	(bus
		(pts
			(xy 386.08 31.75) (xy 383.54 31.75)
		)
		(stroke
			(width 0)
			(type default)
		)
	)
	(polyline
		(pts
			(xy 92.71 172.72) (xy 92.71 171.45)
		)
		(stroke
			(width 0)
			(type default)
		)
	)
	(wire
		(pts
			(xy 82.55 139.7) (xy 82.55 149.86)
		)
		(stroke
			(width 0)
			(type default)
		)
	)
	(wire
		(pts
			(xy 240.03 48.26) (xy 267.97 48.26)
		)
		(stroke
			(width 0)
			(type default)
		)
	)
	(bus
		(pts
			(xy 303.53 31.75) (xy 304.8 33.02)
		)
		(stroke
			(width 0)
			(type default)
		)
	)
	(wire
		(pts
			(xy 193.04 53.34) (xy 214.63 53.34)
		)
		(stroke
			(width 0)
			(type default)
		)
	)
	(wire
		(pts
			(xy 62.23 97.79) (xy 62.23 101.6)
		)
		(stroke
			(width 0)
			(type default)
		)
	)
	(bus
		(pts
			(xy 383.54 38.1) (xy 382.27 39.37)
		)
		(stroke
			(width 0)
			(type default)
		)
	)
	(wire
		(pts
			(xy 52.07 62.23) (xy 85.09 62.23)
		)
		(stroke
			(width 0)
			(type default)
		)
	)
	(bus
		(pts
			(xy 382.27 76.2) (xy 382.27 78.74)
		)
		(stroke
			(width 0)
			(type default)
		)
	)
	(wire
		(pts
			(xy 318.77 36.83) (xy 306.07 36.83)
		)
		(stroke
			(width 0)
			(type default)
		)
	)
	(bus
		(pts
			(xy 303.53 176.53) (xy 303.53 179.07)
		)
		(stroke
			(width 0)
			(type default)
		)
	)
	(bus
		(pts
			(xy 303.53 57.15) (xy 304.8 58.42)
		)
		(stroke
			(width 0)
			(type default)
		)
	)
	(wire
		(pts
			(xy 381 55.88) (xy 363.22 55.88)
		)
		(stroke
			(width 0)
			(type default)
		)
	)
	(wire
		(pts
			(xy 111.76 162.56) (xy 105.41 162.56)
		)
		(stroke
			(width 0)
			(type default)
		)
	)
	(wire
		(pts
			(xy 83.82 105.41) (xy 83.82 107.95)
		)
		(stroke
			(width 0)
			(type default)
		)
	)
	(wire
		(pts
			(xy 135.89 46.99) (xy 135.89 49.53)
		)
		(stroke
			(width 0)
			(type default)
		)
	)
	(wire
		(pts
			(xy 85.09 69.85) (xy 83.82 69.85)
		)
		(stroke
			(width 0)
			(type default)
		)
	)
	(bus
		(pts
			(xy 379.73 241.3) (xy 379.73 243.84)
		)
		(stroke
			(width 0)
			(type default)
		)
	)
	(wire
		(pts
			(xy 307.34 214.63) (xy 320.04 214.63)
		)
		(stroke
			(width 0)
			(type default)
		)
	)
	(wire
		(pts
			(xy 302.26 208.28) (xy 320.04 208.28)
		)
		(stroke
			(width 0)
			(type default)
		)
	)
	(wire
		(pts
			(xy 57.15 43.18) (xy 57.15 46.99)
		)
		(stroke
			(width 0)
			(type default)
		)
	)
	(wire
		(pts
			(xy 59.69 167.64) (xy 85.09 167.64)
		)
		(stroke
			(width 0)
			(type default)
		)
	)
	(polyline
		(pts
			(xy 97.79 219.71) (xy 99.06 218.44)
		)
		(stroke
			(width 0)
			(type default)
		)
	)
	(wire
		(pts
			(xy 193.04 60.96) (xy 214.63 60.96)
		)
		(stroke
			(width 0)
			(type default)
		)
	)
	(wire
		(pts
			(xy 113.03 209.55) (xy 113.03 210.82)
		)
		(stroke
			(width 0)
			(type default)
		)
	)
	(wire
		(pts
			(xy 106.68 236.22) (xy 106.68 248.92)
		)
		(stroke
			(width 0)
			(type default)
		)
	)
	(wire
		(pts
			(xy 210.82 67.31) (xy 213.36 67.31)
		)
		(stroke
			(width 0)
			(type default)
		)
	)
	(bus
		(pts
			(xy 378.46 99.06) (xy 377.19 100.33)
		)
		(stroke
			(width 0)
			(type default)
		)
	)
	(wire
		(pts
			(xy 135.89 105.41) (xy 135.89 113.03)
		)
		(stroke
			(width 0)
			(type default)
		)
	)
	(wire
		(pts
			(xy 210.82 64.77) (xy 213.36 64.77)
		)
		(stroke
			(width 0)
			(type default)
		)
	)
	(bus
		(pts
			(xy 262.89 59.69) (xy 262.89 62.23)
		)
		(stroke
			(width 0)
			(type default)
		)
	)
	(wire
		(pts
			(xy 90.17 40.64) (xy 90.17 41.91)
		)
		(stroke
			(width 0)
			(type default)
		)
	)
	(wire
		(pts
			(xy 41.91 106.68) (xy 41.91 110.49)
		)
		(stroke
			(width 0)
			(type default)
		)
	)
	(polyline
		(pts
			(xy 99.06 162.56) (xy 97.79 161.29)
		)
		(stroke
			(width 0)
			(type default)
		)
	)
	(polyline
		(pts
			(xy 92.71 228.6) (xy 92.71 227.33)
		)
		(stroke
			(width 0)
			(type default)
		)
	)
	(wire
		(pts
			(xy 365.76 133.35) (xy 363.22 133.35)
		)
		(stroke
			(width 0)
			(type default)
		)
	)
	(polyline
		(pts
			(xy 91.44 220.98) (xy 97.79 220.98)
		)
		(stroke
			(width 0)
			(type default)
		)
	)
	(bus
		(pts
			(xy 262.89 64.77) (xy 262.89 67.31)
		)
		(stroke
			(width 0)
			(type default)
		)
	)
	(polyline
		(pts
			(xy 97.79 157.48) (xy 97.79 158.75)
		)
		(stroke
			(width 0)
			(type default)
		)
	)
	(wire
		(pts
			(xy 105.41 236.22) (xy 106.68 236.22)
		)
		(stroke
			(width 0)
			(type default)
		)
	)
	(bus
		(pts
			(xy 190.5 41.91) (xy 190.5 44.45)
		)
		(stroke
			(width 0)
			(type default)
		)
	)
	(wire
		(pts
			(xy 193.04 50.8) (xy 214.63 50.8)
		)
		(stroke
			(width 0)
			(type default)
		)
	)
	(polyline
		(pts
			(xy 97.79 154.94) (xy 97.79 156.21)
		)
		(stroke
			(width 0)
			(type default)
		)
	)
	(bus
		(pts
			(xy 299.72 205.74) (xy 300.99 207.01)
		)
		(stroke
			(width 0)
			(type default)
		)
	)
	(bus
		(pts
			(xy 379.73 157.48) (xy 381 156.21)
		)
		(stroke
			(width 0)
			(type default)
		)
	)
	(bus
		(pts
			(xy 299.72 220.98) (xy 300.99 222.25)
		)
		(stroke
			(width 0)
			(type default)
		)
	)
	(bus
		(pts
			(xy 269.24 46.99) (xy 269.24 49.53)
		)
		(stroke
			(width 0)
			(type default)
		)
	)
	(polyline
		(pts
			(xy 91.44 160.02) (xy 97.79 160.02)
		)
		(stroke
			(width 0)
			(type default)
		)
	)
	(wire
		(pts
			(xy 306.07 55.88) (xy 318.77 55.88)
		)
		(stroke
			(width 0)
			(type default)
		)
	)
	(bus
		(pts
			(xy 379.73 163.83) (xy 379.73 166.37)
		)
		(stroke
			(width 0)
			(type default)
		)
	)
	(bus
		(pts
			(xy 168.91 57.15) (xy 167.64 57.15)
		)
		(stroke
			(width 0)
			(type default)
		)
	)
	(polyline
		(pts
			(xy 97.79 158.75) (xy 99.06 157.48)
		)
		(stroke
			(width 0)
			(type default)
		)
	)
	(bus
		(pts
			(xy 129.54 219.71) (xy 129.54 222.25)
		)
		(stroke
			(width 0)
			(type default)
		)
	)
	(bus
		(pts
			(xy 166.37 114.3) (xy 166.37 116.84)
		)
		(stroke
			(width 0)
			(type default)
		)
	)
	(polyline
		(pts
			(xy 91.44 223.52) (xy 97.79 223.52)
		)
		(stroke
			(width 0)
			(type default)
		)
	)
	(bus
		(pts
			(xy 382.27 71.12) (xy 382.27 73.66)
		)
		(stroke
			(width 0)
			(type default)
		)
	)
	(wire
		(pts
			(xy 307.34 212.09) (xy 320.04 212.09)
		)
		(stroke
			(width 0)
			(type default)
		)
	)
	(bus
		(pts
			(xy 382.27 73.66) (xy 382.27 76.2)
		)
		(stroke
			(width 0)
			(type default)
		)
	)
	(wire
		(pts
			(xy 113.03 139.7) (xy 113.03 140.97)
		)
		(stroke
			(width 0)
			(type default)
		)
	)
	(wire
		(pts
			(xy 105.41 64.77) (xy 125.73 64.77)
		)
		(stroke
			(width 0)
			(type default)
		)
	)
	(wire
		(pts
			(xy 105.41 105.41) (xy 106.68 105.41)
		)
		(stroke
			(width 0)
			(type default)
		)
	)
	(polyline
		(pts
			(xy 99.06 154.94) (xy 97.79 153.67)
		)
		(stroke
			(width 0)
			(type default)
		)
	)
	(wire
		(pts
			(xy 213.36 64.77) (xy 213.36 66.04)
		)
		(stroke
			(width 0)
			(type default)
		)
	)
	(bus
		(pts
			(xy 377.19 105.41) (xy 377.19 107.95)
		)
		(stroke
			(width 0)
			(type default)
		)
	)
	(bus
		(pts
			(xy 269.24 49.53) (xy 269.24 52.07)
		)
		(stroke
			(width 0)
			(type default)
		)
	)
	(bus
		(pts
			(xy 135.89 223.52) (xy 130.81 223.52)
		)
		(stroke
			(width 0)
			(type default)
		)
	)
	(wire
		(pts
			(xy 381 36.83) (xy 363.22 36.83)
		)
		(stroke
			(width 0)
			(type default)
		)
	)
	(wire
		(pts
			(xy 212.09 38.1) (xy 214.63 38.1)
		)
		(stroke
			(width 0)
			(type default)
		)
	)
	(wire
		(pts
			(xy 105.41 110.49) (xy 146.05 110.49)
		)
		(stroke
			(width 0)
			(type default)
		)
	)
	(polyline
		(pts
			(xy 91.44 154.94) (xy 97.79 154.94)
		)
		(stroke
			(width 0)
			(type default)
		)
	)
	(wire
		(pts
			(xy 113.03 201.93) (xy 113.03 203.2)
		)
		(stroke
			(width 0)
			(type default)
		)
	)
	(polyline
		(pts
			(xy 91.44 165.1) (xy 92.71 166.37)
		)
		(stroke
			(width 0)
			(type default)
		)
	)
	(polyline
		(pts
			(xy 92.71 163.83) (xy 91.44 165.1)
		)
		(stroke
			(width 0)
			(type default)
		)
	)
	(wire
		(pts
			(xy 191.77 43.18) (xy 214.63 43.18)
		)
		(stroke
			(width 0)
			(type default)
		)
	)
	(wire
		(pts
			(xy 105.41 248.92) (xy 106.68 248.92)
		)
		(stroke
			(width 0)
			(type default)
		)
	)
	(polyline
		(pts
			(xy 97.79 156.21) (xy 97.79 157.48)
		)
		(stroke
			(width 0)
			(type default)
		)
	)
	(wire
		(pts
			(xy 90.17 91.44) (xy 90.17 92.71)
		)
		(stroke
			(width 0)
			(type default)
		)
	)
	(wire
		(pts
			(xy 381 49.53) (xy 363.22 49.53)
		)
		(stroke
			(width 0)
			(type default)
		)
	)
	(wire
		(pts
			(xy 60.96 233.68) (xy 85.09 233.68)
		)
		(stroke
			(width 0)
			(type default)
		)
	)
	(wire
		(pts
			(xy 306.07 41.91) (xy 318.77 41.91)
		)
		(stroke
			(width 0)
			(type default)
		)
	)
	(wire
		(pts
			(xy 111.76 172.72) (xy 105.41 172.72)
		)
		(stroke
			(width 0)
			(type default)
		)
	)
	(wire
		(pts
			(xy 135.89 97.79) (xy 146.05 97.79)
		)
		(stroke
			(width 0)
			(type default)
		)
	)
	(wire
		(pts
			(xy 193.04 71.12) (xy 214.63 71.12)
		)
		(stroke
			(width 0)
			(type default)
		)
	)
	(wire
		(pts
			(xy 80.01 185.42) (xy 85.09 185.42)
		)
		(stroke
			(width 0)
			(type default)
		)
	)
	(wire
		(pts
			(xy 318.77 48.26) (xy 306.07 48.26)
		)
		(stroke
			(width 0)
			(type default)
		)
	)
	(polyline
		(pts
			(xy 99.06 233.68) (xy 92.71 233.68)
		)
		(stroke
			(width 0)
			(type default)
		)
	)
	(bus
		(pts
			(xy 166.37 58.42) (xy 166.37 60.96)
		)
		(stroke
			(width 0)
			(type default)
		)
	)
	(wire
		(pts
			(xy 125.73 97.79) (xy 130.81 97.79)
		)
		(stroke
			(width 0)
			(type default)
		)
	)
	(wire
		(pts
			(xy 83.82 54.61) (xy 85.09 54.61)
		)
		(stroke
			(width 0)
			(type default)
		)
	)
	(wire
		(pts
			(xy 77.47 146.05) (xy 77.47 147.32)
		)
		(stroke
			(width 0)
			(type default)
		)
	)
	(wire
		(pts
			(xy 72.39 50.8) (xy 72.39 46.99)
		)
		(stroke
			(width 0)
			(type default)
		)
	)
	(wire
		(pts
			(xy 27.94 59.69) (xy 41.91 59.69)
		)
		(stroke
			(width 0)
			(type default)
		)
	)
	(bus
		(pts
			(xy 166.37 109.22) (xy 167.64 107.95)
		)
		(stroke
			(width 0)
			(type default)
		)
	)
	(bus
		(pts
			(xy 304.8 58.42) (xy 304.8 60.96)
		)
		(stroke
			(width 0)
			(type default)
		)
	)
	(wire
		(pts
			(xy 130.81 46.99) (xy 135.89 46.99)
		)
		(stroke
			(width 0)
			(type default)
		)
	)
	(wire
		(pts
			(xy 130.81 95.25) (xy 130.81 97.79)
		)
		(stroke
			(width 0)
			(type default)
		)
	)
	(wire
		(pts
			(xy 363.22 77.47) (xy 381 77.47)
		)
		(stroke
			(width 0)
			(type default)
		)
	)
	(wire
		(pts
			(xy 59.69 157.48) (xy 85.09 157.48)
		)
		(stroke
			(width 0)
			(type default)
		)
	)
	(wire
		(pts
			(xy 105.41 118.11) (xy 115.57 118.11)
		)
		(stroke
			(width 0)
			(type default)
		)
	)
	(wire
		(pts
			(xy 240.03 58.42) (xy 242.57 58.42)
		)
		(stroke
			(width 0)
			(type default)
		)
	)
	(wire
		(pts
			(xy 321.31 186.69) (xy 304.8 186.69)
		)
		(stroke
			(width 0)
			(type default)
		)
	)
	(polyline
		(pts
			(xy 91.44 231.14) (xy 92.71 232.41)
		)
		(stroke
			(width 0)
			(type default)
		)
	)
	(wire
		(pts
			(xy 363.22 86.36) (xy 384.81 86.36)
		)
		(stroke
			(width 0)
			(type default)
		)
	)
	(wire
		(pts
			(xy 363.22 83.82) (xy 384.81 83.82)
		)
		(stroke
			(width 0)
			(type default)
		)
	)
	(wire
		(pts
			(xy 105.41 220.98) (xy 128.27 220.98)
		)
		(stroke
			(width 0)
			(type default)
		)
	)
	(bus
		(pts
			(xy 300.99 224.79) (xy 300.99 227.33)
		)
		(stroke
			(width 0)
			(type default)
		)
	)
	(wire
		(pts
			(xy 83.82 177.8) (xy 83.82 186.69)
		)
		(stroke
			(width 0)
			(type default)
		)
	)
	(wire
		(pts
			(xy 381 53.34) (xy 363.22 53.34)
		)
		(stroke
			(width 0)
			(type default)
		)
	)
	(polyline
		(pts
			(xy 97.79 227.33) (xy 99.06 226.06)
		)
		(stroke
			(width 0)
			(type default)
		)
	)
	(wire
		(pts
			(xy 240.03 53.34) (xy 267.97 53.34)
		)
		(stroke
			(width 0)
			(type default)
		)
	)
	(wire
		(pts
			(xy 115.57 100.33) (xy 115.57 97.79)
		)
		(stroke
			(width 0)
			(type default)
		)
	)
	(bus
		(pts
			(xy 166.37 63.5) (xy 166.37 66.04)
		)
		(stroke
			(width 0)
			(type default)
		)
	)
	(wire
		(pts
			(xy 77.47 203.2) (xy 82.55 203.2)
		)
		(stroke
			(width 0)
			(type default)
		)
	)
	(wire
		(pts
			(xy 80.01 246.38) (xy 80.01 248.92)
		)
		(stroke
			(width 0)
			(type default)
		)
	)
	(wire
		(pts
			(xy 62.23 46.99) (xy 62.23 50.8)
		)
		(stroke
			(width 0)
			(type default)
		)
	)
	(wire
		(pts
			(xy 27.94 110.49) (xy 41.91 110.49)
		)
		(stroke
			(width 0)
			(type default)
		)
	)
	(wire
		(pts
			(xy 111.76 170.18) (xy 105.41 170.18)
		)
		(stroke
			(width 0)
			(type default)
		)
	)
	(wire
		(pts
			(xy 83.82 177.8) (xy 85.09 177.8)
		)
		(stroke
			(width 0)
			(type default)
		)
	)
	(wire
		(pts
			(xy 107.95 139.7) (xy 113.03 139.7)
		)
		(stroke
			(width 0)
			(type default)
		)
	)
	(wire
		(pts
			(xy 135.89 97.79) (xy 135.89 100.33)
		)
		(stroke
			(width 0)
			(type default)
		)
	)
	(wire
		(pts
			(xy 240.03 68.58) (xy 261.62 68.58)
		)
		(stroke
			(width 0)
			(type default)
		)
	)
	(bus
		(pts
			(xy 382.27 33.02) (xy 382.27 35.56)
		)
		(stroke
			(width 0)
			(type default)
		)
	)
	(wire
		(pts
			(xy 83.82 218.44) (xy 83.82 241.3)
		)
		(stroke
			(width 0)
			(type default)
		)
	)
	(wire
		(pts
			(xy 83.82 121.92) (xy 83.82 120.65)
		)
		(stroke
			(width 0)
			(type default)
		)
	)
	(polyline
		(pts
			(xy 92.71 170.18) (xy 92.71 168.91)
		)
		(stroke
			(width 0)
			(type default)
		)
	)
	(polyline
		(pts
			(xy 92.71 166.37) (xy 92.71 165.1)
		)
		(stroke
			(width 0)
			(type default)
		)
	)
	(wire
		(pts
			(xy 41.91 97.79) (xy 52.07 97.79)
		)
		(stroke
			(width 0)
			(type default)
		)
	)
	(wire
		(pts
			(xy 41.91 59.69) (xy 85.09 59.69)
		)
		(stroke
			(width 0)
			(type default)
		)
	)
	(polyline
		(pts
			(xy 97.79 161.29) (xy 99.06 160.02)
		)
		(stroke
			(width 0)
			(type default)
		)
	)
	(wire
		(pts
			(xy 113.03 203.2) (xy 113.03 204.47)
		)
		(stroke
			(width 0)
			(type default)
		)
	)
	(wire
		(pts
			(xy 363.22 80.01) (xy 381 80.01)
		)
		(stroke
			(width 0)
			(type default)
		)
	)
	(wire
		(pts
			(xy 72.39 55.88) (xy 72.39 67.31)
		)
		(stroke
			(width 0)
			(type default)
		)
	)
	(wire
		(pts
			(xy 72.39 67.31) (xy 85.09 67.31)
		)
		(stroke
			(width 0)
			(type default)
		)
	)
	(wire
		(pts
			(xy 146.05 110.49) (xy 165.1 110.49)
		)
		(stroke
			(width 0)
			(type default)
		)
	)
	(wire
		(pts
			(xy 213.36 35.56) (xy 214.63 35.56)
		)
		(stroke
			(width 0)
			(type default)
		)
	)
	(polyline
		(pts
			(xy 92.71 231.14) (xy 92.71 229.87)
		)
		(stroke
			(width 0)
			(type default)
		)
	)
	(bus
		(pts
			(xy 381 240.03) (xy 379.73 241.3)
		)
		(stroke
			(width 0)
			(type default)
		)
	)
	(wire
		(pts
			(xy 83.82 54.61) (xy 83.82 57.15)
		)
		(stroke
			(width 0)
			(type default)
		)
	)
	(wire
		(pts
			(xy 302.26 242.57) (xy 320.04 242.57)
		)
		(stroke
			(width 0)
			(type default)
		)
	)
	(bus
		(pts
			(xy 166.37 109.22) (xy 166.37 111.76)
		)
		(stroke
			(width 0)
			(type default)
		)
	)
	(bus
		(pts
			(xy 304.8 60.96) (xy 304.8 63.5)
		)
		(stroke
			(width 0)
			(type default)
		)
	)
	(wire
		(pts
			(xy 62.23 231.14) (xy 85.09 231.14)
		)
		(stroke
			(width 0)
			(type default)
		)
	)
	(bus
		(pts
			(xy 190.5 44.45) (xy 190.5 46.99)
		)
		(stroke
			(width 0)
			(type default)
		)
	)
	(bus
		(pts
			(xy 383.54 69.85) (xy 382.27 71.12)
		)
		(stroke
			(width 0)
			(type default)
		)
	)
	(wire
		(pts
			(xy 105.41 228.6) (xy 128.27 228.6)
		)
		(stroke
			(width 0)
			(type default)
		)
	)
	(wire
		(pts
			(xy 125.73 97.79) (xy 125.73 100.33)
		)
		(stroke
			(width 0)
			(type default)
		)
	)
	(wire
		(pts
			(xy 213.36 68.58) (xy 214.63 68.58)
		)
		(stroke
			(width 0)
			(type default)
		)
	)
	(bus
		(pts
			(xy 264.16 58.42) (xy 262.89 59.69)
		)
		(stroke
			(width 0)
			(type default)
		)
	)
	(polyline
		(pts
			(xy 92.71 232.41) (xy 92.71 231.14)
		)
		(stroke
			(width 0)
			(type default)
		)
	)
	(wire
		(pts
			(xy 306.07 39.37) (xy 318.77 39.37)
		)
		(stroke
			(width 0)
			(type default)
		)
	)
	(wire
		(pts
			(xy 57.15 95.25) (xy 57.15 97.79)
		)
		(stroke
			(width 0)
			(type default)
		)
	)
	(wire
		(pts
			(xy 306.07 64.77) (xy 318.77 64.77)
		)
		(stroke
			(width 0)
			(type default)
		)
	)
	(wire
		(pts
			(xy 210.82 35.56) (xy 212.09 35.56)
		)
		(stroke
			(width 0)
			(type default)
		)
	)
	(wire
		(pts
			(xy 105.41 54.61) (xy 106.68 54.61)
		)
		(stroke
			(width 0)
			(type default)
		)
	)
	(bus
		(pts
			(xy 381 162.56) (xy 379.73 163.83)
		)
		(stroke
			(width 0)
			(type default)
		)
	)
	(polyline
		(pts
			(xy 99.06 170.18) (xy 92.71 170.18)
		)
		(stroke
			(width 0)
			(type default)
		)
	)
	(wire
		(pts
			(xy 381 40.64) (xy 363.22 40.64)
		)
		(stroke
			(width 0)
			(type default)
		)
	)
	(wire
		(pts
			(xy 107.95 203.2) (xy 107.95 213.36)
		)
		(stroke
			(width 0)
			(type default)
		)
	)
	(wire
		(pts
			(xy 193.04 63.5) (xy 214.63 63.5)
		)
		(stroke
			(width 0)
			(type default)
		)
	)
	(wire
		(pts
			(xy 105.41 59.69) (xy 146.05 59.69)
		)
		(stroke
			(width 0)
			(type default)
		)
	)
	(bus
		(pts
			(xy 297.18 232.41) (xy 299.72 232.41)
		)
		(stroke
			(width 0)
			(type default)
		)
	)
	(wire
		(pts
			(xy 111.76 157.48) (xy 105.41 157.48)
		)
		(stroke
			(width 0)
			(type default)
		)
	)
	(wire
		(pts
			(xy 321.31 177.8) (xy 304.8 177.8)
		)
		(stroke
			(width 0)
			(type default)
		)
	)
	(bus
		(pts
			(xy 304.8 40.64) (xy 304.8 43.18)
		)
		(stroke
			(width 0)
			(type default)
		)
	)
	(bus
		(pts
			(xy 377.19 102.87) (xy 377.19 105.41)
		)
		(stroke
			(width 0)
			(type default)
		)
	)
	(polyline
		(pts
			(xy 97.79 158.75) (xy 97.79 160.02)
		)
		(stroke
			(width 0)
			(type default)
		)
	)
	(polyline
		(pts
			(xy 92.71 229.87) (xy 91.44 231.14)
		)
		(stroke
			(width 0)
			(type default)
		)
	)
	(polyline
		(pts
			(xy 92.71 166.37) (xy 91.44 167.64)
		)
		(stroke
			(width 0)
			(type default)
		)
	)
	(polyline
		(pts
			(xy 92.71 168.91) (xy 92.71 167.64)
		)
		(stroke
			(width 0)
			(type default)
		)
	)
	(wire
		(pts
			(xy 100.33 91.44) (xy 100.33 92.71)
		)
		(stroke
			(width 0)
			(type default)
		)
	)
	(wire
		(pts
			(xy 62.23 106.68) (xy 62.23 115.57)
		)
		(stroke
			(width 0)
			(type default)
		)
	)
	(wire
		(pts
			(xy 77.47 138.43) (xy 77.47 139.7)
		)
		(stroke
			(width 0)
			(type default)
		)
	)
	(wire
		(pts
			(xy 115.57 46.99) (xy 125.73 46.99)
		)
		(stroke
			(width 0)
			(type default)
		)
	)
	(wire
		(pts
			(xy 80.01 248.92) (xy 85.09 248.92)
		)
		(stroke
			(width 0)
			(type default)
		)
	)
	(wire
		(pts
			(xy 191.77 48.26) (xy 214.63 48.26)
		)
		(stroke
			(width 0)
			(type default)
		)
	)
	(wire
		(pts
			(xy 210.82 33.02) (xy 213.36 33.02)
		)
		(stroke
			(width 0)
			(type default)
		)
	)
	(polyline
		(pts
			(xy 91.44 218.44) (xy 97.79 218.44)
		)
		(stroke
			(width 0)
			(type default)
		)
	)
	(bus
		(pts
			(xy 382.27 45.72) (xy 382.27 48.26)
		)
		(stroke
			(width 0)
			(type default)
		)
	)
	(bus
		(pts
			(xy 130.81 223.52) (xy 129.54 224.79)
		)
		(stroke
			(width 0)
			(type default)
		)
	)
	(wire
		(pts
			(xy 125.73 46.99) (xy 130.81 46.99)
		)
		(stroke
			(width 0)
			(type default)
		)
	)
	(wire
		(pts
			(xy 302.26 231.14) (xy 320.04 231.14)
		)
		(stroke
			(width 0)
			(type default)
		)
	)
	(wire
		(pts
			(xy 115.57 105.41) (xy 115.57 118.11)
		)
		(stroke
			(width 0)
			(type default)
		)
	)
	(wire
		(pts
			(xy 52.07 97.79) (xy 52.07 101.6)
		)
		(stroke
			(width 0)
			(type default)
		)
	)
	(polyline
		(pts
			(xy 92.71 232.41) (xy 91.44 233.68)
		)
		(stroke
			(width 0)
			(type default)
		)
	)
	(wire
		(pts
			(xy 306.07 50.8) (xy 318.77 50.8)
		)
		(stroke
			(width 0)
			(type default)
		)
	)
	(polyline
		(pts
			(xy 97.79 217.17) (xy 97.79 218.44)
		)
		(stroke
			(width 0)
			(type default)
		)
	)
	(wire
		(pts
			(xy 80.01 245.11) (xy 80.01 246.38)
		)
		(stroke
			(width 0)
			(type default)
		)
	)
	(bus
		(pts
			(xy 383.54 50.8) (xy 382.27 52.07)
		)
		(stroke
			(width 0)
			(type default)
		)
	)
	(polyline
		(pts
			(xy 97.79 219.71) (xy 97.79 220.98)
		)
		(stroke
			(width 0)
			(type default)
		)
	)
	(wire
		(pts
			(xy 106.68 120.65) (xy 105.41 120.65)
		)
		(stroke
			(width 0)
			(type default)
		)
	)
	(bus
		(pts
			(xy 299.72 232.41) (xy 300.99 233.68)
		)
		(stroke
			(width 0)
			(type default)
		)
	)
	(wire
		(pts
			(xy 125.73 64.77) (xy 165.1 64.77)
		)
		(stroke
			(width 0)
			(type default)
		)
	)
	(wire
		(pts
			(xy 363.22 104.14) (xy 375.92 104.14)
		)
		(stroke
			(width 0)
			(type default)
		)
	)
	(polyline
		(pts
			(xy 97.79 226.06) (xy 97.79 227.33)
		)
		(stroke
			(width 0)
			(type default)
		)
	)
	(bus
		(pts
			(xy 383.54 162.56) (xy 381 162.56)
		)
		(stroke
			(width 0)
			(type default)
		)
	)
	(wire
		(pts
			(xy 52.07 46.99) (xy 52.07 50.8)
		)
		(stroke
			(width 0)
			(type default)
		)
	)
	(polyline
		(pts
			(xy 97.79 161.29) (xy 97.79 162.56)
		)
		(stroke
			(width 0)
			(type default)
		)
	)
	(wire
		(pts
			(xy 80.01 246.38) (xy 85.09 246.38)
		)
		(stroke
			(width 0)
			(type default)
		)
	)
	(bus
		(pts
			(xy 386.08 50.8) (xy 383.54 50.8)
		)
		(stroke
			(width 0)
			(type default)
		)
	)
	(wire
		(pts
			(xy 306.07 34.29) (xy 318.77 34.29)
		)
		(stroke
			(width 0)
			(type default)
		)
	)
	(wire
		(pts
			(xy 304.8 154.94) (xy 321.31 154.94)
		)
		(stroke
			(width 0)
			(type default)
		)
	)
	(wire
		(pts
			(xy 72.39 106.68) (xy 72.39 118.11)
		)
		(stroke
			(width 0)
			(type default)
		)
	)
	(bus
		(pts
			(xy 190.5 39.37) (xy 190.5 41.91)
		)
		(stroke
			(width 0)
			(type default)
		)
	)
	(bus
		(pts
			(xy 300.99 233.68) (xy 300.99 236.22)
		)
		(stroke
			(width 0)
			(type default)
		)
	)
	(polyline
		(pts
			(xy 91.44 233.68) (xy 92.71 234.95)
		)
		(stroke
			(width 0)
			(type default)
		)
	)
	(wire
		(pts
			(xy 363.22 245.11) (xy 378.46 245.11)
		)
		(stroke
			(width 0)
			(type default)
		)
	)
	(wire
		(pts
			(xy 212.09 35.56) (xy 212.09 38.1)
		)
		(stroke
			(width 0)
			(type default)
		)
	)
	(wire
		(pts
			(xy 363.22 101.6) (xy 375.92 101.6)
		)
		(stroke
			(width 0)
			(type default)
		)
	)
	(polyline
		(pts
			(xy 99.06 165.1) (xy 92.71 165.1)
		)
		(stroke
			(width 0)
			(type default)
		)
	)
	(wire
		(pts
			(xy 59.69 228.6) (xy 85.09 228.6)
		)
		(stroke
			(width 0)
			(type default)
		)
	)
	(wire
		(pts
			(xy 125.73 54.61) (xy 125.73 64.77)
		)
		(stroke
			(width 0)
			(type default)
		)
	)
	(wire
		(pts
			(xy 27.94 113.03) (xy 52.07 113.03)
		)
		(stroke
			(width 0)
			(type default)
		)
	)
	(wire
		(pts
			(xy 363.22 74.93) (xy 381 74.93)
		)
		(stroke
			(width 0)
			(type default)
		)
	)
	(wire
		(pts
			(xy 83.82 107.95) (xy 85.09 107.95)
		)
		(stroke
			(width 0)
			(type default)
		)
	)
	(bus
		(pts
			(xy 300.99 222.25) (xy 300.99 224.79)
		)
		(stroke
			(width 0)
			(type default)
		)
	)
	(wire
		(pts
			(xy 363.22 106.68) (xy 375.92 106.68)
		)
		(stroke
			(width 0)
			(type default)
		)
	)
	(wire
		(pts
			(xy 72.39 118.11) (xy 85.09 118.11)
		)
		(stroke
			(width 0)
			(type default)
		)
	)
	(polyline
		(pts
			(xy 97.79 162.56) (xy 97.79 163.83)
		)
		(stroke
			(width 0)
			(type default)
		)
	)
	(polyline
		(pts
			(xy 97.79 218.44) (xy 97.79 219.71)
		)
		(stroke
			(width 0)
			(type default)
		)
	)
	(wire
		(pts
			(xy 361.95 158.75) (xy 378.46 158.75)
		)
		(stroke
			(width 0)
			(type default)
		)
	)
	(bus
		(pts
			(xy 300.99 227.33) (xy 300.99 229.87)
		)
		(stroke
			(width 0)
			(type default)
		)
	)
	(polyline
		(pts
			(xy 99.06 226.06) (xy 97.79 224.79)
		)
		(stroke
			(width 0)
			(type default)
		)
	)
	(polyline
		(pts
			(xy 99.06 220.98) (xy 97.79 219.71)
		)
		(stroke
			(width 0)
			(type default)
		)
	)
	(bus
		(pts
			(xy 130.81 218.44) (xy 129.54 219.71)
		)
		(stroke
			(width 0)
			(type default)
		)
	)
	(wire
		(pts
			(xy 306.07 53.34) (xy 318.77 53.34)
		)
		(stroke
			(width 0)
			(type default)
		)
	)
	(wire
		(pts
			(xy 381 34.29) (xy 363.22 34.29)
		)
		(stroke
			(width 0)
			(type default)
		)
	)
	(bus
		(pts
			(xy 269.24 52.07) (xy 269.24 54.61)
		)
		(stroke
			(width 0)
			(type default)
		)
	)
	(wire
		(pts
			(xy 146.05 97.79) (xy 146.05 100.33)
		)
		(stroke
			(width 0)
			(type default)
		)
	)
	(bus
		(pts
			(xy 303.53 45.72) (xy 304.8 46.99)
		)
		(stroke
			(width 0)
			(type default)
		)
	)
	(wire
		(pts
			(xy 240.03 60.96) (xy 261.62 60.96)
		)
		(stroke
			(width 0)
			(type default)
		)
	)
	(polyline
		(pts
			(xy 91.44 172.72) (xy 92.71 173.99)
		)
		(stroke
			(width 0)
			(type default)
		)
	)
	(wire
		(pts
			(xy 62.23 55.88) (xy 62.23 64.77)
		)
		(stroke
			(width 0)
			(type default)
		)
	)
	(bus
		(pts
			(xy 379.73 157.48) (xy 379.73 160.02)
		)
		(stroke
			(width 0)
			(type default)
		)
	)
	(polyline
		(pts
			(xy 99.06 236.22) (xy 92.71 236.22)
		)
		(stroke
			(width 0)
			(type default)
		)
	)
	(polyline
		(pts
			(xy 97.79 222.25) (xy 99.06 220.98)
		)
		(stroke
			(width 0)
			(type default)
		)
	)
	(wire
		(pts
			(xy 107.95 139.7) (xy 107.95 149.86)
		)
		(stroke
			(width 0)
			(type default)
		)
	)
	(wire
		(pts
			(xy 27.94 67.31) (xy 72.39 67.31)
		)
		(stroke
			(width 0)
			(type default)
		)
	)
	(wire
		(pts
			(xy 115.57 67.31) (xy 165.1 67.31)
		)
		(stroke
			(width 0)
			(type default)
		)
	)
	(wire
		(pts
			(xy 59.69 172.72) (xy 85.09 172.72)
		)
		(stroke
			(width 0)
			(type default)
		)
	)
	(wire
		(pts
			(xy 302.26 237.49) (xy 320.04 237.49)
		)
		(stroke
			(width 0)
			(type default)
		)
	)
	(wire
		(pts
			(xy 105.41 185.42) (xy 106.68 185.42)
		)
		(stroke
			(width 0)
			(type default)
		)
	)
	(wire
		(pts
			(xy 116.84 231.14) (xy 105.41 231.14)
		)
		(stroke
			(width 0)
			(type default)
		)
	)
	(wire
		(pts
			(xy 111.76 154.94) (xy 105.41 154.94)
		)
		(stroke
			(width 0)
			(type default)
		)
	)
	(wire
		(pts
			(xy 125.73 46.99) (xy 125.73 49.53)
		)
		(stroke
			(width 0)
			(type default)
		)
	)
	(wire
		(pts
			(xy 306.07 62.23) (xy 318.77 62.23)
		)
		(stroke
			(width 0)
			(type default)
		)
	)
	(wire
		(pts
			(xy 57.15 46.99) (xy 62.23 46.99)
		)
		(stroke
			(width 0)
			(type default)
		)
	)
	(wire
		(pts
			(xy 240.03 63.5) (xy 261.62 63.5)
		)
		(stroke
			(width 0)
			(type default)
		)
	)
	(wire
		(pts
			(xy 82.55 203.2) (xy 82.55 213.36)
		)
		(stroke
			(width 0)
			(type default)
		)
	)
	(polyline
		(pts
			(xy 92.71 165.1) (xy 92.71 163.83)
		)
		(stroke
			(width 0)
			(type default)
		)
	)
	(wire
		(pts
			(xy 146.05 54.61) (xy 146.05 59.69)
		)
		(stroke
			(width 0)
			(type default)
		)
	)
	(bus
		(pts
			(xy 383.54 156.21) (xy 381 156.21)
		)
		(stroke
			(width 0)
			(type default)
		)
	)
	(wire
		(pts
			(xy 100.33 34.29) (xy 100.33 35.56)
		)
		(stroke
			(width 0)
			(type default)
		)
	)
	(wire
		(pts
			(xy 321.31 184.15) (xy 304.8 184.15)
		)
		(stroke
			(width 0)
			(type default)
		)
	)
	(wire
		(pts
			(xy 105.41 67.31) (xy 115.57 67.31)
		)
		(stroke
			(width 0)
			(type default)
		)
	)
	(bus
		(pts
			(xy 297.18 205.74) (xy 299.72 205.74)
		)
		(stroke
			(width 0)
			(type default)
		)
	)
	(wire
		(pts
			(xy 363.22 63.5) (xy 373.38 63.5)
		)
		(stroke
			(width 0)
			(type default)
		)
	)
	(wire
		(pts
			(xy 27.94 118.11) (xy 72.39 118.11)
		)
		(stroke
			(width 0)
			(type default)
		)
	)
	(wire
		(pts
			(xy 41.91 55.88) (xy 41.91 59.69)
		)
		(stroke
			(width 0)
			(type default)
		)
	)
	(wire
		(pts
			(xy 381 46.99) (xy 363.22 46.99)
		)
		(stroke
			(width 0)
			(type default)
		)
	)
	(wire
		(pts
			(xy 146.05 46.99) (xy 146.05 49.53)
		)
		(stroke
			(width 0)
			(type default)
		)
	)
	(wire
		(pts
			(xy 59.69 154.94) (xy 85.09 154.94)
		)
		(stroke
			(width 0)
			(type default)
		)
	)
	(wire
		(pts
			(xy 193.04 55.88) (xy 214.63 55.88)
		)
		(stroke
			(width 0)
			(type default)
		)
	)
	(bus
		(pts
			(xy 304.8 46.99) (xy 304.8 49.53)
		)
		(stroke
			(width 0)
			(type default)
		)
	)
	(wire
		(pts
			(xy 83.82 160.02) (xy 85.09 160.02)
		)
		(stroke
			(width 0)
			(type default)
		)
	)
	(wire
		(pts
			(xy 306.07 59.69) (xy 318.77 59.69)
		)
		(stroke
			(width 0)
			(type default)
		)
	)
	(wire
		(pts
			(xy 105.41 149.86) (xy 107.95 149.86)
		)
		(stroke
			(width 0)
			(type default)
		)
	)
	(wire
		(pts
			(xy 100.33 40.64) (xy 100.33 41.91)
		)
		(stroke
			(width 0)
			(type default)
		)
	)
	(wire
		(pts
			(xy 363.22 60.96) (xy 373.38 60.96)
		)
		(stroke
			(width 0)
			(type default)
		)
	)
	(bus
		(pts
			(xy 300.99 238.76) (xy 300.99 241.3)
		)
		(stroke
			(width 0)
			(type default)
		)
	)
	(bus
		(pts
			(xy 383.54 44.45) (xy 382.27 45.72)
		)
		(stroke
			(width 0)
			(type default)
		)
	)
	(wire
		(pts
			(xy 135.89 113.03) (xy 165.1 113.03)
		)
		(stroke
			(width 0)
			(type default)
		)
	)
	(wire
		(pts
			(xy 135.89 46.99) (xy 146.05 46.99)
		)
		(stroke
			(width 0)
			(type default)
		)
	)
	(wire
		(pts
			(xy 52.07 97.79) (xy 57.15 97.79)
		)
		(stroke
			(width 0)
			(type default)
		)
	)
	(polyline
		(pts
			(xy 91.44 157.48) (xy 97.79 157.48)
		)
		(stroke
			(width 0)
			(type default)
		)
	)
	(wire
		(pts
			(xy 125.73 105.41) (xy 125.73 115.57)
		)
		(stroke
			(width 0)
			(type default)
		)
	)
	(bus
		(pts
			(xy 168.91 113.03) (xy 167.64 113.03)
		)
		(stroke
			(width 0)
			(type default)
		)
	)
	(bus
		(pts
			(xy 166.37 63.5) (xy 167.64 62.23)
		)
		(stroke
			(width 0)
			(type default)
		)
	)
	(polyline
		(pts
			(xy 92.71 234.95) (xy 91.44 236.22)
		)
		(stroke
			(width 0)
			(type default)
		)
	)
	(wire
		(pts
			(xy 361.95 161.29) (xy 378.46 161.29)
		)
		(stroke
			(width 0)
			(type default)
		)
	)
	(wire
		(pts
			(xy 82.55 213.36) (xy 85.09 213.36)
		)
		(stroke
			(width 0)
			(type default)
		)
	)
	(wire
		(pts
			(xy 62.23 97.79) (xy 72.39 97.79)
		)
		(stroke
			(width 0)
			(type default)
		)
	)
	(wire
		(pts
			(xy 83.82 218.44) (xy 85.09 218.44)
		)
		(stroke
			(width 0)
			(type default)
		)
	)
	(bus
		(pts
			(xy 304.8 49.53) (xy 304.8 52.07)
		)
		(stroke
			(width 0)
			(type default)
		)
	)
	(wire
		(pts
			(xy 115.57 54.61) (xy 115.57 67.31)
		)
		(stroke
			(width 0)
			(type default)
		)
	)
	(polyline
		(pts
			(xy 92.71 171.45) (xy 91.44 172.72)
		)
		(stroke
			(width 0)
			(type default)
		)
	)
	(wire
		(pts
			(xy 191.77 45.72) (xy 214.63 45.72)
		)
		(stroke
			(width 0)
			(type default)
		)
	)
	(wire
		(pts
			(xy 59.69 170.18) (xy 85.09 170.18)
		)
		(stroke
			(width 0)
			(type default)
		)
	)
	(wire
		(pts
			(xy 307.34 219.71) (xy 320.04 219.71)
		)
		(stroke
			(width 0)
			(type default)
		)
	)
	(bus
		(pts
			(xy 304.8 35.56) (xy 304.8 38.1)
		)
		(stroke
			(width 0)
			(type default)
		)
	)
	(wire
		(pts
			(xy 240.03 71.12) (xy 261.62 71.12)
		)
		(stroke
			(width 0)
			(type default)
		)
	)
	(polyline
		(pts
			(xy 92.71 229.87) (xy 92.71 228.6)
		)
		(stroke
			(width 0)
			(type default)
		)
	)
	(wire
		(pts
			(xy 105.41 226.06) (xy 128.27 226.06)
		)
		(stroke
			(width 0)
			(type default)
		)
	)
	(wire
		(pts
			(xy 27.94 115.57) (xy 62.23 115.57)
		)
		(stroke
			(width 0)
			(type default)
		)
	)
	(bus
		(pts
			(xy 386.08 44.45) (xy 383.54 44.45)
		)
		(stroke
			(width 0)
			(type default)
		)
	)
	(polyline
		(pts
			(xy 97.79 224.79) (xy 97.79 226.06)
		)
		(stroke
			(width 0)
			(type default)
		)
	)
	(wire
		(pts
			(xy 304.8 165.1) (xy 321.31 165.1)
		)
		(stroke
			(width 0)
			(type default)
		)
	)
	(wire
		(pts
			(xy 82.55 149.86) (xy 85.09 149.86)
		)
		(stroke
			(width 0)
			(type default)
		)
	)
	(bus
		(pts
			(xy 168.91 62.23) (xy 167.64 62.23)
		)
		(stroke
			(width 0)
			(type default)
		)
	)
	(wire
		(pts
			(xy 240.03 55.88) (xy 267.97 55.88)
		)
		(stroke
			(width 0)
			(type default)
		)
	)
	(bus
		(pts
			(xy 129.54 224.79) (xy 129.54 227.33)
		)
		(stroke
			(width 0)
			(type default)
		)
	)
	(polyline
		(pts
			(xy 91.44 170.18) (xy 92.71 171.45)
		)
		(stroke
			(width 0)
			(type default)
		)
	)
	(polyline
		(pts
			(xy 91.44 226.06) (xy 97.79 226.06)
		)
		(stroke
			(width 0)
			(type default)
		)
	)
	(wire
		(pts
			(xy 113.03 138.43) (xy 113.03 139.7)
		)
		(stroke
			(width 0)
			(type default)
		)
	)
	(polyline
		(pts
			(xy 91.44 236.22) (xy 92.71 237.49)
		)
		(stroke
			(width 0)
			(type default)
		)
	)
	(polyline
		(pts
			(xy 91.44 167.64) (xy 92.71 168.91)
		)
		(stroke
			(width 0)
			(type default)
		)
	)
	(wire
		(pts
			(xy 135.89 54.61) (xy 135.89 62.23)
		)
		(stroke
			(width 0)
			(type default)
		)
	)
	(wire
		(pts
			(xy 83.82 53.34) (xy 83.82 54.61)
		)
		(stroke
			(width 0)
			(type default)
		)
	)
	(bus
		(pts
			(xy 383.54 31.75) (xy 382.27 33.02)
		)
		(stroke
			(width 0)
			(type default)
		)
	)
	(wire
		(pts
			(xy 302.26 234.95) (xy 320.04 234.95)
		)
		(stroke
			(width 0)
			(type default)
		)
	)
	(wire
		(pts
			(xy 62.23 46.99) (xy 72.39 46.99)
		)
		(stroke
			(width 0)
			(type default)
		)
	)
	(wire
		(pts
			(xy 363.22 68.58) (xy 373.38 68.58)
		)
		(stroke
			(width 0)
			(type default)
		)
	)
	(wire
		(pts
			(xy 77.47 139.7) (xy 82.55 139.7)
		)
		(stroke
			(width 0)
			(type default)
		)
	)
	(wire
		(pts
			(xy 130.81 97.79) (xy 135.89 97.79)
		)
		(stroke
			(width 0)
			(type default)
		)
	)
	(wire
		(pts
			(xy 83.82 120.65) (xy 85.09 120.65)
		)
		(stroke
			(width 0)
			(type default)
		)
	)
	(wire
		(pts
			(xy 106.68 53.34) (xy 106.68 54.61)
		)
		(stroke
			(width 0)
			(type default)
		)
	)
	(wire
		(pts
			(xy 27.94 64.77) (xy 62.23 64.77)
		)
		(stroke
			(width 0)
			(type default)
		)
	)
	(wire
		(pts
			(xy 111.76 165.1) (xy 105.41 165.1)
		)
		(stroke
			(width 0)
			(type default)
		)
	)
	(wire
		(pts
			(xy 304.8 152.4) (xy 321.31 152.4)
		)
		(stroke
			(width 0)
			(type default)
		)
	)
	(wire
		(pts
			(xy 105.41 115.57) (xy 125.73 115.57)
		)
		(stroke
			(width 0)
			(type default)
		)
	)
	(wire
		(pts
			(xy 52.07 106.68) (xy 52.07 113.03)
		)
		(stroke
			(width 0)
			(type default)
		)
	)
	(polyline
		(pts
			(xy 97.79 223.52) (xy 97.79 224.79)
		)
		(stroke
			(width 0)
			(type default)
		)
	)
	(wire
		(pts
			(xy 59.69 162.56) (xy 85.09 162.56)
		)
		(stroke
			(width 0)
			(type default)
		)
	)
	(wire
		(pts
			(xy 193.04 73.66) (xy 214.63 73.66)
		)
		(stroke
			(width 0)
			(type default)
		)
	)
	(bus
		(pts
			(xy 166.37 114.3) (xy 167.64 113.03)
		)
		(stroke
			(width 0)
			(type default)
		)
	)
	(wire
		(pts
			(xy 59.69 165.1) (xy 85.09 165.1)
		)
		(stroke
			(width 0)
			(type default)
		)
	)
	(polyline
		(pts
			(xy 92.71 168.91) (xy 91.44 170.18)
		)
		(stroke
			(width 0)
			(type default)
		)
	)
	(polyline
		(pts
			(xy 97.79 220.98) (xy 97.79 222.25)
		)
		(stroke
			(width 0)
			(type default)
		)
	)
	(bus
		(pts
			(xy 262.89 62.23) (xy 262.89 64.77)
		)
		(stroke
			(width 0)
			(type default)
		)
	)
	(polyline
		(pts
			(xy 97.79 153.67) (xy 97.79 154.94)
		)
		(stroke
			(width 0)
			(type default)
		)
	)
	(wire
		(pts
			(xy 100.33 85.09) (xy 100.33 86.36)
		)
		(stroke
			(width 0)
			(type default)
		)
	)
	(wire
		(pts
			(xy 361.95 165.1) (xy 378.46 165.1)
		)
		(stroke
			(width 0)
			(type default)
		)
	)
	(wire
		(pts
			(xy 363.22 66.04) (xy 373.38 66.04)
		)
		(stroke
			(width 0)
			(type default)
		)
	)
	(wire
		(pts
			(xy 80.01 181.61) (xy 80.01 182.88)
		)
		(stroke
			(width 0)
			(type default)
		)
	)
	(wire
		(pts
			(xy 213.36 67.31) (xy 213.36 68.58)
		)
		(stroke
			(width 0)
			(type default)
		)
	)
	(wire
		(pts
			(xy 52.07 46.99) (xy 57.15 46.99)
		)
		(stroke
			(width 0)
			(type default)
		)
	)
	(polyline
		(pts
			(xy 99.06 231.14) (xy 92.71 231.14)
		)
		(stroke
			(width 0)
			(type default)
		)
	)
	(wire
		(pts
			(xy 191.77 40.64) (xy 214.63 40.64)
		)
		(stroke
			(width 0)
			(type default)
		)
	)
	(wire
		(pts
			(xy 306.07 67.31) (xy 318.77 67.31)
		)
		(stroke
			(width 0)
			(type default)
		)
	)
	(wire
		(pts
			(xy 240.03 73.66) (xy 261.62 73.66)
		)
		(stroke
			(width 0)
			(type default)
		)
	)
	(polyline
		(pts
			(xy 97.79 222.25) (xy 97.79 223.52)
		)
		(stroke
			(width 0)
			(type default)
		)
	)
	(wire
		(pts
			(xy 304.8 161.29) (xy 321.31 161.29)
		)
		(stroke
			(width 0)
			(type default)
		)
	)
	(polyline
		(pts
			(xy 99.06 228.6) (xy 92.71 228.6)
		)
		(stroke
			(width 0)
			(type default)
		)
	)
	(wire
		(pts
			(xy 321.31 180.34) (xy 304.8 180.34)
		)
		(stroke
			(width 0)
			(type default)
		)
	)
	(wire
		(pts
			(xy 240.03 50.8) (xy 267.97 50.8)
		)
		(stroke
			(width 0)
			(type default)
		)
	)
	(wire
		(pts
			(xy 306.07 69.85) (xy 318.77 69.85)
		)
		(stroke
			(width 0)
			(type default)
		)
	)
	(bus
		(pts
			(xy 303.53 176.53) (xy 302.26 175.26)
		)
		(stroke
			(width 0)
			(type default)
		)
	)
	(wire
		(pts
			(xy 80.01 182.88) (xy 80.01 185.42)
		)
		(stroke
			(width 0)
			(type default)
		)
	)
	(polyline
		(pts
			(xy 99.06 167.64) (xy 92.71 167.64)
		)
		(stroke
			(width 0)
			(type default)
		)
	)
	(wire
		(pts
			(xy 302.26 223.52) (xy 320.04 223.52)
		)
		(stroke
			(width 0)
			(type default)
		)
	)
	(wire
		(pts
			(xy 41.91 50.8) (xy 41.91 46.99)
		)
		(stroke
			(width 0)
			(type default)
		)
	)
	(wire
		(pts
			(xy 83.82 160.02) (xy 83.82 177.8)
		)
		(stroke
			(width 0)
			(type default)
		)
	)
	(polyline
		(pts
			(xy 92.71 237.49) (xy 92.71 236.22)
		)
		(stroke
			(width 0)
			(type default)
		)
	)
	(wire
		(pts
			(xy 213.36 33.02) (xy 213.36 35.56)
		)
		(stroke
			(width 0)
			(type default)
		)
	)
	(polyline
		(pts
			(xy 511.81 -13.97) (xy 511.81 -13.97)
		)
		(stroke
			(width 0)
			(type default)
		)
	)
	(polyline
		(pts
			(xy 97.79 160.02) (xy 97.79 161.29)
		)
		(stroke
			(width 0)
			(type default)
		)
	)
	(polyline
		(pts
			(xy 97.79 156.21) (xy 99.06 154.94)
		)
		(stroke
			(width 0)
			(type default)
		)
	)
	(bus
		(pts
			(xy 382.27 39.37) (xy 382.27 41.91)
		)
		(stroke
			(width 0)
			(type default)
		)
	)
	(wire
		(pts
			(xy 361.95 167.64) (xy 378.46 167.64)
		)
		(stroke
			(width 0)
			(type default)
		)
	)
	(wire
		(pts
			(xy 213.36 66.04) (xy 214.63 66.04)
		)
		(stroke
			(width 0)
			(type default)
		)
	)
	(wire
		(pts
			(xy 72.39 101.6) (xy 72.39 97.79)
		)
		(stroke
			(width 0)
			(type default)
		)
	)
	(polyline
		(pts
			(xy 97.79 163.83) (xy 99.06 162.56)
		)
		(stroke
			(width 0)
			(type default)
		)
	)
	(wire
		(pts
			(xy 105.41 62.23) (xy 135.89 62.23)
		)
		(stroke
			(width 0)
			(type default)
		)
	)
	(polyline
		(pts
			(xy 92.71 227.33) (xy 91.44 228.6)
		)
		(stroke
			(width 0)
			(type default)
		)
	)
	(wire
		(pts
			(xy 62.23 64.77) (xy 85.09 64.77)
		)
		(stroke
			(width 0)
			(type default)
		)
	)
	(wire
		(pts
			(xy 105.41 223.52) (xy 128.27 223.52)
		)
		(stroke
			(width 0)
			(type default)
		)
	)
	(wire
		(pts
			(xy 52.07 113.03) (xy 85.09 113.03)
		)
		(stroke
			(width 0)
			(type default)
		)
	)
	(polyline
		(pts
			(xy 92.71 233.68) (xy 92.71 232.41)
		)
		(stroke
			(width 0)
			(type default)
		)
	)
	(wire
		(pts
			(xy 304.8 167.64) (xy 321.31 167.64)
		)
		(stroke
			(width 0)
			(type default)
		)
	)
	(wire
		(pts
			(xy 240.03 66.04) (xy 261.62 66.04)
		)
		(stroke
			(width 0)
			(type default)
		)
	)
	(wire
		(pts
			(xy 115.57 97.79) (xy 125.73 97.79)
		)
		(stroke
			(width 0)
			(type default)
		)
	)
	(wire
		(pts
			(xy 83.82 105.41) (xy 85.09 105.41)
		)
		(stroke
			(width 0)
			(type default)
		)
	)
	(wire
		(pts
			(xy 77.47 201.93) (xy 77.47 203.2)
		)
		(stroke
			(width 0)
			(type default)
		)
	)
	(bus
		(pts
			(xy 189.23 38.1) (xy 190.5 39.37)
		)
		(stroke
			(width 0)
			(type default)
		)
	)
	(label "~{USBC2_INT}_1V8"
		(at 193.04 71.12 0)
		(effects
			(font
				(size 1.27 1.27)
			)
			(justify left bottom)
		)
	)
	(label "SPI3.MISO"
		(at 306.07 67.31 0)
		(effects
			(font
				(size 1.27 1.27)
			)
			(justify left bottom)
		)
	)
	(label "CAN3.DOUT"
		(at 378.46 55.88 180)
		(effects
			(font
				(size 1.27 1.27)
			)
			(justify right bottom)
		)
	)
	(label "GPIO.USER_LED1"
		(at 193.04 43.18 0)
		(effects
			(font
				(size 1.27 1.27)
			)
			(justify left bottom)
		)
	)
	(label "CAN1.DOUT"
		(at 378.46 43.18 180)
		(effects
			(font
				(size 1.27 1.27)
			)
			(justify right bottom)
		)
	)
	(label "I2S_{M.2}.FS"
		(at 307.34 214.63 0)
		(effects
			(font
				(size 1.27 1.27)
			)
			(justify left bottom)
		)
	)
	(label "USBC2_ID_1V8"
		(at 193.04 53.34 0)
		(effects
			(font
				(size 1.27 1.27)
			)
			(justify left bottom)
		)
	)
	(label "I2C3_SDA_1V8"
		(at 304.8 173.99 0)
		(effects
			(font
				(size 1.27 1.27)
			)
			(justify left bottom)
		)
	)
	(label "CAN0.DIN"
		(at 378.46 34.29 180)
		(effects
			(font
				(size 1.27 1.27)
			)
			(justify right bottom)
		)
	)
	(label "I2S3.FS"
		(at 318.77 247.65 180)
		(effects
			(font
				(size 1.27 1.27)
			)
			(justify right bottom)
		)
	)
	(label "GPIO.USER_BTN1"
		(at 193.04 48.26 0)
		(effects
			(font
				(size 1.27 1.27)
			)
			(justify left bottom)
		)
	)
	(label "USBC2_VBUS_DET_1V8"
		(at 59.69 170.18 0)
		(effects
			(font
				(size 1.27 1.27)
			)
			(justify left bottom)
		)
	)
	(label "I2S2.SDIN"
		(at 303.53 231.14 0)
		(effects
			(font
				(size 1.27 1.27)
			)
			(justify left bottom)
		)
	)
	(label "UART3_DEBUG_RX_1V8"
		(at 59.69 228.6 0)
		(effects
			(font
				(size 1.27 1.27)
			)
			(justify left bottom)
		)
	)
	(label "UART3_DEBUG_TX_1V8"
		(at 59.69 226.06 0)
		(effects
			(font
				(size 1.27 1.27)
			)
			(justify left bottom)
		)
	)
	(label "I2C5_SCL_1V8"
		(at 304.8 184.15 0)
		(effects
			(font
				(size 1.27 1.27)
			)
			(justify left bottom)
		)
	)
	(label "I2C2_SDA_1V8"
		(at 304.8 167.64 0)
		(effects
			(font
				(size 1.27 1.27)
			)
			(justify left bottom)
		)
	)
	(label "I2C0.SCL"
		(at 152.4 59.69 0)
		(effects
			(font
				(size 1.27 1.27)
			)
			(justify left bottom)
		)
	)
	(label "UART2.RTS"
		(at 381 72.39 180)
		(effects
			(font
				(size 1.27 1.27)
			)
			(justify right bottom)
		)
	)
	(label "GPIO.MCLK01"
		(at 314.96 208.28 180)
		(effects
			(font
				(size 1.27 1.27)
			)
			(justify right bottom)
		)
	)
	(label "I2C7.SCL"
		(at 377.19 158.75 180)
		(effects
			(font
				(size 1.27 1.27)
			)
			(justify right bottom)
		)
	)
	(label "SPI1.~{CS1}"
		(at 306.07 36.83 0)
		(effects
			(font
				(size 1.27 1.27)
			)
			(justify left bottom)
		)
	)
	(label "I2S3.SDOUT"
		(at 303.53 240.03 0)
		(effects
			(font
				(size 1.27 1.27)
			)
			(justify left bottom)
		)
	)
	(label "I2S_{M.2}.SDIN"
		(at 307.34 219.71 0)
		(effects
			(font
				(size 1.27 1.27)
			)
			(justify left bottom)
		)
	)
	(label "CAN0.DOUT"
		(at 378.46 36.83 180)
		(effects
			(font
				(size 1.27 1.27)
			)
			(justify right bottom)
		)
	)
	(label "SPI2.MOSI"
		(at 306.07 55.88 0)
		(effects
			(font
				(size 1.27 1.27)
			)
			(justify left bottom)
		)
	)
	(label "I2S_{M.2}.CLK"
		(at 307.34 212.09 0)
		(effects
			(font
				(size 1.27 1.27)
			)
			(justify left bottom)
		)
	)
	(label "SPI2.SCK"
		(at 306.07 50.8 0)
		(effects
			(font
				(size 1.27 1.27)
			)
			(justify left bottom)
		)
	)
	(label "I2C2_SDA_1V8"
		(at 27.94 113.03 0)
		(effects
			(font
				(size 1.27 1.27)
			)
			(justify left bottom)
		)
	)
	(label "M2_E.W_DIS_1"
		(at 110.49 220.98 0)
		(effects
			(font
				(size 1.27 1.27)
			)
			(justify left bottom)
		)
	)
	(label "CAM_CTRL.VSYNC_CAM1"
		(at 242.57 50.8 0)
		(effects
			(font
				(size 1.27 1.27)
			)
			(justify left bottom)
		)
	)
	(label "USBC1_FLG_1V8"
		(at 62.23 231.14 0)
		(effects
			(font
				(size 1.27 1.27)
			)
			(justify left bottom)
		)
	)
	(label "M2_E.W_DIS_2"
		(at 110.49 223.52 0)
		(effects
			(font
				(size 1.27 1.27)
			)
			(justify left bottom)
		)
	)
	(label "SPI3.MOSI"
		(at 306.07 69.85 0)
		(effects
			(font
				(size 1.27 1.27)
			)
			(justify left bottom)
		)
	)
	(label "SPI3.~{CS0}"
		(at 306.07 59.69 0)
		(effects
			(font
				(size 1.27 1.27)
			)
			(justify left bottom)
		)
	)
	(label "I2C2_SCL_1V8"
		(at 27.94 110.49 0)
		(effects
			(font
				(size 1.27 1.27)
			)
			(justify left bottom)
		)
	)
	(label "UART2.RX"
		(at 381 80.01 180)
		(effects
			(font
				(size 1.27 1.27)
			)
			(justify right bottom)
		)
	)
	(label "CAM_CTRL.VSYNC_CAM2"
		(at 242.57 53.34 0)
		(effects
			(font
				(size 1.27 1.27)
			)
			(justify left bottom)
		)
	)
	(label "I2C7.SDA"
		(at 377.19 161.29 180)
		(effects
			(font
				(size 1.27 1.27)
			)
			(justify right bottom)
		)
	)
	(label "I2C8.SCL"
		(at 377.19 165.1 180)
		(effects
			(font
				(size 1.27 1.27)
			)
			(justify right bottom)
		)
	)
	(label "UART3_DEBUG_RX_1V8"
		(at 384.81 86.36 180)
		(effects
			(font
				(size 1.27 1.27)
			)
			(justify right bottom)
		)
	)
	(label "UART1.RTS"
		(at 373.38 60.96 180)
		(effects
			(font
				(size 1.27 1.27)
			)
			(justify right bottom)
		)
	)
	(label "UART2.CTS"
		(at 381 74.93 180)
		(effects
			(font
				(size 1.27 1.27)
			)
			(justify right bottom)
		)
	)
	(label "I2C1_SCL_1V8"
		(at 304.8 158.75 0)
		(effects
			(font
				(size 1.27 1.27)
			)
			(justify left bottom)
		)
	)
	(label "UART3_DEBUG.RX"
		(at 110.49 228.6 0)
		(effects
			(font
				(size 1.27 1.27)
			)
			(justify left bottom)
		)
	)
	(label "I2S3.CLK"
		(at 303.53 234.95 0)
		(effects
			(font
				(size 1.27 1.27)
			)
			(justify left bottom)
		)
	)
	(label "I2C_{CONN}.SCL"
		(at 152.4 115.57 0)
		(effects
			(font
				(size 1.27 1.27)
			)
			(justify left bottom)
		)
	)
	(label "SPI2.MISO"
		(at 306.07 53.34 0)
		(effects
			(font
				(size 1.27 1.27)
			)
			(justify left bottom)
		)
	)
	(label "I2C0.SDA"
		(at 152.4 62.23 0)
		(effects
			(font
				(size 1.27 1.27)
			)
			(justify left bottom)
		)
	)
	(label "SPI1.MOSI"
		(at 306.07 44.45 0)
		(effects
			(font
				(size 1.27 1.27)
			)
			(justify left bottom)
		)
	)
	(label "GPIO.21"
		(at 260.35 66.04 180)
		(effects
			(font
				(size 1.27 1.27)
			)
			(justify right bottom)
		)
	)
	(label "I2S3.FS"
		(at 303.53 237.49 0)
		(effects
			(font
				(size 1.27 1.27)
			)
			(justify left bottom)
		)
	)
	(label "I2C_{SYS}.SDA"
		(at 152.4 113.03 0)
		(effects
			(font
				(size 1.27 1.27)
			)
			(justify left bottom)
		)
	)
	(label "I2C0_SCL_1V8"
		(at 304.8 152.4 0)
		(effects
			(font
				(size 1.27 1.27)
			)
			(justify left bottom)
		)
	)
	(label "USBC2_ID_1V8"
		(at 59.69 165.1 0)
		(effects
			(font
				(size 1.27 1.27)
			)
			(justify left bottom)
		)
	)
	(label "I2C5_SDA_1V8"
		(at 304.8 186.69 0)
		(effects
			(font
				(size 1.27 1.27)
			)
			(justify left bottom)
		)
	)
	(label "SPI3.~{CS1}"
		(at 306.07 62.23 0)
		(effects
			(font
				(size 1.27 1.27)
			)
			(justify left bottom)
		)
	)
	(label "SFP_LEDY_1V8"
		(at 59.69 154.94 0)
		(effects
			(font
				(size 1.27 1.27)
			)
			(justify left bottom)
		)
	)
	(label "I2C_{CAM}.SDA"
		(at 306.07 180.34 0)
		(effects
			(font
				(size 1.27 1.27)
			)
			(justify left bottom)
		)
	)
	(label "I2C_{SFP}.SCL"
		(at 152.4 67.31 0)
		(effects
			(font
				(size 1.27 1.27)
			)
			(justify left bottom)
		)
	)
	(label "I2C0_SDA_1V8"
		(at 27.94 59.69 0)
		(effects
			(font
				(size 1.27 1.27)
			)
			(justify left bottom)
		)
	)
	(label "I2C3_SCL_1V8"
		(at 27.94 67.31 0)
		(effects
			(font
				(size 1.27 1.27)
			)
			(justify left bottom)
		)
	)
	(label "I2S_{M.2}.SDOUT"
		(at 307.34 217.17 0)
		(effects
			(font
				(size 1.27 1.27)
			)
			(justify left bottom)
		)
	)
	(label "USBC2_PEN_1V8"
		(at 193.04 55.88 0)
		(effects
			(font
				(size 1.27 1.27)
			)
			(justify left bottom)
		)
	)
	(label "GPIO.27"
		(at 260.35 68.58 180)
		(effects
			(font
				(size 1.27 1.27)
			)
			(justify right bottom)
		)
	)
	(label "GPIO_EXP_IRQ_1V8"
		(at 262.89 45.72 180)
		(effects
			(font
				(size 1.27 1.27)
			)
			(justify right bottom)
		)
	)
	(label "~{USBC2_INT}_1V8"
		(at 59.69 167.64 0)
		(effects
			(font
				(size 1.27 1.27)
			)
			(justify left bottom)
		)
	)
	(label "UART1.CTS"
		(at 373.38 63.5 180)
		(effects
			(font
				(size 1.27 1.27)
			)
			(justify right bottom)
		)
	)
	(label "I2C_{SYS}.SCL"
		(at 152.4 110.49 0)
		(effects
			(font
				(size 1.27 1.27)
			)
			(justify left bottom)
		)
	)
	(label "GPIO.USER_LED0"
		(at 193.04 40.64 0)
		(effects
			(font
				(size 1.27 1.27)
			)
			(justify left bottom)
		)
	)
	(label "I2S2.CLK"
		(at 303.53 223.52 0)
		(effects
			(font
				(size 1.27 1.27)
			)
			(justify left bottom)
		)
	)
	(label "SPI1.~{CS0}"
		(at 306.07 34.29 0)
		(effects
			(font
				(size 1.27 1.27)
			)
			(justify left bottom)
		)
	)
	(label "UART5.CTS"
		(at 375.92 104.14 180)
		(effects
			(font
				(size 1.27 1.27)
			)
			(justify right bottom)
		)
	)
	(label "I2S2.FS"
		(at 303.53 226.06 0)
		(effects
			(font
				(size 1.27 1.27)
			)
			(justify left bottom)
		)
	)
	(label "I2C3_SCL_1V8"
		(at 304.8 171.45 0)
		(effects
			(font
				(size 1.27 1.27)
			)
			(justify left bottom)
		)
	)
	(label "GPIO.USER_BTN0"
		(at 193.04 45.72 0)
		(effects
			(font
				(size 1.27 1.27)
			)
			(justify left bottom)
		)
	)
	(label "USBC2_PEN_1V8"
		(at 59.69 162.56 0)
		(effects
			(font
				(size 1.27 1.27)
			)
			(justify left bottom)
		)
	)
	(label "GPIO_EXP_IRQ_1V8"
		(at 60.96 233.68 0)
		(effects
			(font
				(size 1.27 1.27)
			)
			(justify left bottom)
		)
	)
	(label "CAN3.DIN"
		(at 378.46 53.34 180)
		(effects
			(font
				(size 1.27 1.27)
			)
			(justify right bottom)
		)
	)
	(label "I2C5_SDA_1V8"
		(at 27.94 118.11 0)
		(effects
			(font
				(size 1.27 1.27)
			)
			(justify left bottom)
		)
	)
	(label "I2C0_SDA_1V8"
		(at 304.8 154.94 0)
		(effects
			(font
				(size 1.27 1.27)
			)
			(justify left bottom)
		)
	)
	(label "UART2.TX"
		(at 381 77.47 180)
		(effects
			(font
				(size 1.27 1.27)
			)
			(justify right bottom)
		)
	)
	(label "I2C8.SDA"
		(at 377.19 167.64 180)
		(effects
			(font
				(size 1.27 1.27)
			)
			(justify right bottom)
		)
	)
	(label "M2_E_W_DIS_1_1V8"
		(at 59.69 220.98 0)
		(effects
			(font
				(size 1.27 1.27)
			)
			(justify left bottom)
		)
	)
	(label "~{PDC_I2C1_IRQ}_1V8"
		(at 261.62 73.66 180)
		(effects
			(font
				(size 1.27 1.27)
			)
			(justify right bottom)
		)
	)
	(label "UART5.RX"
		(at 375.92 109.22 180)
		(effects
			(font
				(size 1.27 1.27)
			)
			(justify right bottom)
		)
	)
	(label "UART5.TX"
		(at 375.92 106.68 180)
		(effects
			(font
				(size 1.27 1.27)
			)
			(justify right bottom)
		)
	)
	(label "UART5.RTS"
		(at 375.92 101.6 180)
		(effects
			(font
				(size 1.27 1.27)
			)
			(justify right bottom)
		)
	)
	(label "GPIO.20"
		(at 260.35 63.5 180)
		(effects
			(font
				(size 1.27 1.27)
			)
			(justify right bottom)
		)
	)
	(label "I2C_{SFP}.SDA"
		(at 152.4 64.77 0)
		(effects
			(font
				(size 1.27 1.27)
			)
			(justify left bottom)
		)
	)
	(label "I2C1_SDA_1V8"
		(at 304.8 161.29 0)
		(effects
			(font
				(size 1.27 1.27)
			)
			(justify left bottom)
		)
	)
	(label "CAN1.DIN"
		(at 378.46 40.64 180)
		(effects
			(font
				(size 1.27 1.27)
			)
			(justify right bottom)
		)
	)
	(label "I2C5_SCL_1V8"
		(at 27.94 115.57 0)
		(effects
			(font
				(size 1.27 1.27)
			)
			(justify left bottom)
		)
	)
	(label "I2S2.SDOUT"
		(at 303.53 228.6 0)
		(effects
			(font
				(size 1.27 1.27)
			)
			(justify left bottom)
		)
	)
	(label "SFP_LEDG_1V8"
		(at 193.04 76.2 0)
		(effects
			(font
				(size 1.27 1.27)
			)
			(justify left bottom)
		)
	)
	(label "M2_E_W_DIS_1_1V8"
		(at 193.04 60.96 0)
		(effects
			(font
				(size 1.27 1.27)
			)
			(justify left bottom)
		)
	)
	(label "SPI3.SCK"
		(at 306.07 64.77 0)
		(effects
			(font
				(size 1.27 1.27)
			)
			(justify left bottom)
		)
	)
	(label "UART3_DEBUG_TX_1V8"
		(at 384.81 83.82 180)
		(effects
			(font
				(size 1.27 1.27)
			)
			(justify right bottom)
		)
	)
	(label "I2S3.SDIN"
		(at 303.53 242.57 0)
		(effects
			(font
				(size 1.27 1.27)
			)
			(justify left bottom)
		)
	)
	(label "CAN2.DIN"
		(at 378.46 46.99 180)
		(effects
			(font
				(size 1.27 1.27)
			)
			(justify right bottom)
		)
	)
	(label "M2_E_W_DIS_2_1V8"
		(at 59.69 223.52 0)
		(effects
			(font
				(size 1.27 1.27)
			)
			(justify left bottom)
		)
	)
	(label "SFP_LEDY_1V8"
		(at 193.04 73.66 0)
		(effects
			(font
				(size 1.27 1.27)
			)
			(justify left bottom)
		)
	)
	(label "I2C3_SDA_1V8"
		(at 27.94 64.77 0)
		(effects
			(font
				(size 1.27 1.27)
			)
			(justify left bottom)
		)
	)
	(label "I2C2_SCL_1V8"
		(at 304.8 165.1 0)
		(effects
			(font
				(size 1.27 1.27)
			)
			(justify left bottom)
		)
	)
	(label "UART3_DEBUG.TX"
		(at 110.49 226.06 0)
		(effects
			(font
				(size 1.27 1.27)
			)
			(justify left bottom)
		)
	)
	(label "USBC2_VBUS_DET_1V8"
		(at 261.62 71.12 180)
		(effects
			(font
				(size 1.27 1.27)
			)
			(justify right bottom)
		)
	)
	(label "I2C_{CAM}.SCL"
		(at 306.07 177.8 0)
		(effects
			(font
				(size 1.27 1.27)
			)
			(justify left bottom)
		)
	)
	(label "GPIO.18"
		(at 260.35 60.96 180)
		(effects
			(font
				(size 1.27 1.27)
			)
			(justify right bottom)
		)
	)
	(label "SPI2.~{CS0}"
		(at 306.07 48.26 0)
		(effects
			(font
				(size 1.27 1.27)
			)
			(justify left bottom)
		)
	)
	(label "CAN2.DOUT"
		(at 378.46 49.53 180)
		(effects
			(font
				(size 1.27 1.27)
			)
			(justify right bottom)
		)
	)
	(label "CAM_CTRL.VSYNC_CAM3"
		(at 242.57 55.88 0)
		(effects
			(font
				(size 1.27 1.27)
			)
			(justify left bottom)
		)
	)
	(label "I2C0_SCL_1V8"
		(at 27.94 62.23 0)
		(effects
			(font
				(size 1.27 1.27)
			)
			(justify left bottom)
		)
	)
	(label "SPI1.MISO"
		(at 306.07 41.91 0)
		(effects
			(font
				(size 1.27 1.27)
			)
			(justify left bottom)
		)
	)
	(label "~{PDC_I2C1_IRQ}_1V8"
		(at 59.69 172.72 0)
		(effects
			(font
				(size 1.27 1.27)
			)
			(justify left bottom)
		)
	)
	(label "M2_E_W_DIS_2_1V8"
		(at 193.04 63.5 0)
		(effects
			(font
				(size 1.27 1.27)
			)
			(justify left bottom)
		)
	)
	(label "USBC1_FLG_1V8"
		(at 193.04 50.8 0)
		(effects
			(font
				(size 1.27 1.27)
			)
			(justify left bottom)
		)
	)
	(label "SFP_LEDG_1V8"
		(at 59.69 157.48 0)
		(effects
			(font
				(size 1.27 1.27)
			)
			(justify left bottom)
		)
	)
	(label "I2C_{CONN}.SDA"
		(at 152.4 118.11 0)
		(effects
			(font
				(size 1.27 1.27)
			)
			(justify left bottom)
		)
	)
	(label "UART1.TX"
		(at 373.38 66.04 180)
		(effects
			(font
				(size 1.27 1.27)
			)
			(justify right bottom)
		)
	)
	(label "GPIO.MCLK02"
		(at 365.76 242.57 0)
		(effects
			(font
				(size 1.27 1.27)
			)
			(justify left bottom)
		)
	)
	(label "GPIO.MCLK03"
		(at 365.76 245.11 0)
		(effects
			(font
				(size 1.27 1.27)
			)
			(justify left bottom)
		)
	)
	(label "SPI1.SCK"
		(at 306.07 39.37 0)
		(effects
			(font
				(size 1.27 1.27)
			)
			(justify left bottom)
		)
	)
	(label "CAM_CTRL.VSYNC_CAM0"
		(at 242.57 48.26 0)
		(effects
			(font
				(size 1.27 1.27)
			)
			(justify left bottom)
		)
	)
	(label "UART1.RX"
		(at 373.38 68.58 180)
		(effects
			(font
				(size 1.27 1.27)
			)
			(justify right bottom)
		)
	)
	(hierarchical_label "I2S3{I2S}"
		(shape bidirectional)
		(at 297.18 232.41 180)
		(effects
			(font
				(size 1.27 1.27)
			)
			(justify right)
		)
	)
	(hierarchical_label "USBC1_FLG"
		(shape input)
		(at 116.84 231.14 0)
		(effects
			(font
				(size 1.27 1.27)
			)
			(justify left)
		)
	)
	(hierarchical_label "GPIO{GPIO}"
		(shape bidirectional)
		(at 383.54 240.03 0)
		(effects
			(font
				(size 1.27 1.27)
			)
			(justify left)
		)
	)
	(hierarchical_label "UART5{UART}"
		(shape bidirectional)
		(at 378.46 99.06 0)
		(effects
			(font
				(size 1.27 1.27)
			)
			(justify left)
		)
	)
	(hierarchical_label "GPIO{GPIO}"
		(shape bidirectional)
		(at 186.69 38.1 180)
		(effects
			(font
				(size 1.27 1.27)
			)
			(justify right)
		)
	)
	(hierarchical_label "FMC_PRESENT"
		(shape bidirectional)
		(at 210.82 64.77 180)
		(effects
			(font
				(size 1.27 1.27)
			)
			(justify right)
		)
	)
	(hierarchical_label "CAM_CTRL{CAM_CTRL}"
		(shape bidirectional)
		(at 270.51 45.72 0)
		(effects
			(font
				(size 1.27 1.27)
			)
			(justify left)
		)
	)
	(hierarchical_label "USBC2_PEN"
		(shape output)
		(at 111.76 162.56 0)
		(effects
			(font
				(size 1.27 1.27)
			)
			(justify left)
		)
	)
	(hierarchical_label "FAN_PWM"
		(shape output)
		(at 365.76 135.89 0)
		(effects
			(font
				(size 1.27 1.27)
			)
			(justify left)
		)
	)
	(hierarchical_label "I2C0{I2C}"
		(shape bidirectional)
		(at 168.91 57.15 0)
		(effects
			(font
				(size 1.27 1.27)
			)
			(justify left)
		)
	)
	(hierarchical_label "I2C_{SYS}{I2C}"
		(shape bidirectional)
		(at 168.91 107.95 0)
		(effects
			(font
				(size 1.27 1.27)
			)
			(justify left)
		)
	)
	(hierarchical_label "SPI2{SPI}"
		(shape bidirectional)
		(at 303.53 45.72 180)
		(effects
			(font
				(size 1.27 1.27)
			)
			(justify right)
		)
	)
	(hierarchical_label "USBC2_VBUS_DET"
		(shape input)
		(at 111.76 170.18 0)
		(effects
			(font
				(size 1.27 1.27)
			)
			(justify left)
		)
	)
	(hierarchical_label "CAN1{CAN}"
		(shape bidirectional)
		(at 386.08 38.1 0)
		(effects
			(font
				(size 1.27 1.27)
			)
			(justify left)
		)
	)
	(hierarchical_label "I2C_{CONN}{I2C}"
		(shape bidirectional)
		(at 168.91 113.03 0)
		(effects
			(font
				(size 1.27 1.27)
			)
			(justify left)
		)
	)
	(hierarchical_label "I2C_{SFP}{I2C}"
		(shape bidirectional)
		(at 168.91 62.23 0)
		(effects
			(font
				(size 1.27 1.27)
			)
			(justify left)
		)
	)
	(hierarchical_label "I2C7{I2C}"
		(shape bidirectional)
		(at 383.54 156.21 0)
		(effects
			(font
				(size 1.27 1.27)
			)
			(justify left)
		)
	)
	(hierarchical_label "M2_E{M2_E}"
		(shape bidirectional)
		(at 133.35 218.44 0)
		(effects
			(font
				(size 1.27 1.27)
			)
			(justify left)
		)
	)
	(hierarchical_label "FMC_PRSNT_M2C_L"
		(shape bidirectional)
		(at 210.82 67.31 180)
		(effects
			(font
				(size 1.27 1.27)
			)
			(justify right)
		)
	)
	(hierarchical_label "SPI1{SPI}"
		(shape bidirectional)
		(at 303.53 31.75 180)
		(effects
			(font
				(size 1.27 1.27)
			)
			(justify right)
		)
	)
	(hierarchical_label "FAN_TACH"
		(shape input)
		(at 365.76 133.35 0)
		(effects
			(font
				(size 1.27 1.27)
			)
			(justify left)
		)
	)
	(hierarchical_label "I2C_{CAM}{I2C}"
		(shape bidirectional)
		(at 302.26 175.26 180)
		(effects
			(font
				(size 1.27 1.27)
			)
			(justify right)
		)
	)
	(hierarchical_label "SFP_LEDY"
		(shape output)
		(at 111.76 154.94 0)
		(effects
			(font
				(size 1.27 1.27)
			)
			(justify left)
		)
	)
	(hierarchical_label "I2C8{I2C}"
		(shape bidirectional)
		(at 383.54 162.56 0)
		(effects
			(font
				(size 1.27 1.27)
			)
			(justify left)
		)
	)
	(hierarchical_label "UART2{UART}"
		(shape bidirectional)
		(at 383.54 69.85 0)
		(effects
			(font
				(size 1.27 1.27)
			)
			(justify left)
		)
	)
	(hierarchical_label "USBC2_ID"
		(shape input)
		(at 111.76 165.1 0)
		(effects
			(font
				(size 1.27 1.27)
			)
			(justify left)
		)
	)
	(hierarchical_label "FMC_PG_M2C"
		(shape bidirectional)
		(at 210.82 33.02 180)
		(effects
			(font
				(size 1.27 1.27)
			)
			(justify right)
		)
	)
	(hierarchical_label "FMC_PG_C2M"
		(shape bidirectional)
		(at 210.82 35.56 180)
		(effects
			(font
				(size 1.27 1.27)
			)
			(justify right)
		)
	)
	(hierarchical_label "SFP_LEDG"
		(shape output)
		(at 111.76 157.48 0)
		(effects
			(font
				(size 1.27 1.27)
			)
			(justify left)
		)
	)
	(hierarchical_label "SPI3{SPI}"
		(shape bidirectional)
		(at 303.53 57.15 180)
		(effects
			(font
				(size 1.27 1.27)
			)
			(justify right)
		)
	)
	(hierarchical_label "I2S2{I2S}"
		(shape bidirectional)
		(at 297.18 220.98 180)
		(effects
			(font
				(size 1.27 1.27)
			)
			(justify right)
		)
	)
	(hierarchical_label "~{PDC_I2C1_IRQ}"
		(shape input)
		(at 111.76 172.72 0)
		(effects
			(font
				(size 1.27 1.27)
			)
			(justify left)
		)
	)
	(hierarchical_label "GPIO_EXP_IRQ"
		(shape input)
		(at 116.84 233.68 0)
		(effects
			(font
				(size 1.27 1.27)
			)
			(justify left)
		)
	)
	(hierarchical_label "GPIO{GPIO}"
		(shape bidirectional)
		(at 264.16 58.42 0)
		(effects
			(font
				(size 1.27 1.27)
			)
			(justify left)
		)
	)
	(hierarchical_label "GPIO{GPIO}"
		(shape bidirectional)
		(at 297.18 205.74 180)
		(effects
			(font
				(size 1.27 1.27)
			)
			(justify right)
		)
	)
	(hierarchical_label "MOD_ABS"
		(shape input)
		(at 242.57 58.42 0)
		(effects
			(font
				(size 1.27 1.27)
			)
			(justify left)
		)
	)
	(hierarchical_label "CAN0{CAN}"
		(shape bidirectional)
		(at 386.08 31.75 0)
		(effects
			(font
				(size 1.27 1.27)
			)
			(justify left)
		)
	)
	(hierarchical_label "CAN2{CAN}"
		(shape bidirectional)
		(at 386.08 44.45 0)
		(effects
			(font
				(size 1.27 1.27)
			)
			(justify left)
		)
	)
	(hierarchical_label "~{USBC2_INT}"
		(shape input)
		(at 111.76 167.64 0)
		(effects
			(font
				(size 1.27 1.27)
			)
			(justify left)
		)
	)
	(hierarchical_label "UART3_DEBUG{UART}"
		(shape bidirectional)
		(at 135.89 223.52 0)
		(effects
			(font
				(size 1.27 1.27)
			)
			(justify left)
		)
	)
	(hierarchical_label "CAN3{CAN}"
		(shape bidirectional)
		(at 386.08 50.8 0)
		(effects
			(font
				(size 1.27 1.27)
			)
			(justify left)
		)
	)
	(symbol
		(lib_id "antmicroResistors0402:R_2k2_0402")
		(at 135.89 49.53 270)
		(unit 1)
		(exclude_from_sim no)
		(in_bom yes)
		(on_board yes)
		(dnp no)
		(fields_autoplaced yes)
		(property "Reference" "R373"
			(at 138.43 50.8 90)
			(effects
				(font
					(size 1.27 1.27)
					(thickness 0.15)
				)
				(justify left)
			)
		)
		(property "Value" "R_2k2_0402"
			(at 123.19 69.85 0)
			(effects
				(font
					(size 1.27 1.27)
					(thickness 0.15)
				)
				(justify left bottom)
				(hide yes)
			)
		)
		(property "Footprint" "antmicro-footprints:R_0402_1005Metric"
			(at 120.65 69.85 0)
			(effects
				(font
					(size 1.27 1.27)
					(thickness 0.15)
				)
				(justify left bottom)
				(hide yes)
			)
		)
		(property "Datasheet" "https://www.bourns.com/docs/product-datasheets/cr.pdf"
			(at 118.11 69.85 0)
			(effects
				(font
					(size 1.27 1.27)
					(thickness 0.15)
				)
				(justify left bottom)
				(hide yes)
			)
		)
		(property "Description" "SMD Chip Resistor, 2.2 kohm, ± 1%, 62.5 mW, 0402 [1005 Metric], Thick Film, General Purpose"
			(at 105.41 69.85 0)
			(effects
				(font
					(size 1.27 1.27)
				)
				(justify left bottom)
				(hide yes)
			)
		)
		(property "MPN" "CR0402-FX-2201GLF"
			(at 115.57 69.85 0)
			(effects
				(font
					(size 1.27 1.27)
					(thickness 0.15)
				)
				(justify left bottom)
				(hide yes)
			)
		)
		(property "Manufacturer" "Bourns"
			(at 113.03 69.85 0)
			(effects
				(font
					(size 1.27 1.27)
					(thickness 0.15)
				)
				(justify left bottom)
				(hide yes)
			)
		)
		(property "License" "Apache-2.0"
			(at 110.49 69.85 0)
			(effects
				(font
					(size 1.27 1.27)
					(thickness 0.15)
				)
				(justify left bottom)
				(hide yes)
			)
		)
		(property "Author" "Antmicro"
			(at 107.95 69.85 0)
			(effects
				(font
					(size 1.27 1.27)
					(thickness 0.15)
				)
				(justify left bottom)
				(hide yes)
			)
		)
		(property "Val" "2k2"
			(at 138.43 53.34 90)
			(effects
				(font
					(size 1.27 1.27)
					(thickness 0.15)
				)
				(justify left)
			)
		)
		(property "Tolerance" "1%"
			(at 125.73 69.85 0)
			(effects
				(font
					(size 1.27 1.27)
				)
				(justify left bottom)
				(hide yes)
			)
		)
		(pin "2"
		)
		(pin "1"
		)
		(instances
			(project "jetson-agx-thor-baseboard"
				(path ""
					(reference "R373")
					(unit 1)
				)
			)
		)
	)
	(symbol
		(lib_id "antmicroResistors0402:R_2k2_0402")
		(at 115.57 100.33 270)
		(unit 1)
		(exclude_from_sim no)
		(in_bom yes)
		(on_board yes)
		(dnp no)
		(fields_autoplaced yes)
		(property "Reference" "R361"
			(at 118.11 101.6 90)
			(effects
				(font
					(size 1.27 1.27)
					(thickness 0.15)
				)
				(justify left)
			)
		)
		(property "Value" "R_2k2_0402"
			(at 102.87 120.65 0)
			(effects
				(font
					(size 1.27 1.27)
					(thickness 0.15)
				)
				(justify left bottom)
				(hide yes)
			)
		)
		(property "Footprint" "antmicro-footprints:R_0402_1005Metric"
			(at 100.33 120.65 0)
			(effects
				(font
					(size 1.27 1.27)
					(thickness 0.15)
				)
				(justify left bottom)
				(hide yes)
			)
		)
		(property "Datasheet" "https://www.bourns.com/docs/product-datasheets/cr.pdf"
			(at 97.79 120.65 0)
			(effects
				(font
					(size 1.27 1.27)
					(thickness 0.15)
				)
				(justify left bottom)
				(hide yes)
			)
		)
		(property "Description" "SMD Chip Resistor, 2.2 kohm, ± 1%, 62.5 mW, 0402 [1005 Metric], Thick Film, General Purpose"
			(at 85.09 120.65 0)
			(effects
				(font
					(size 1.27 1.27)
				)
				(justify left bottom)
				(hide yes)
			)
		)
		(property "MPN" "CR0402-FX-2201GLF"
			(at 95.25 120.65 0)
			(effects
				(font
					(size 1.27 1.27)
					(thickness 0.15)
				)
				(justify left bottom)
				(hide yes)
			)
		)
		(property "Manufacturer" "Bourns"
			(at 92.71 120.65 0)
			(effects
				(font
					(size 1.27 1.27)
					(thickness 0.15)
				)
				(justify left bottom)
				(hide yes)
			)
		)
		(property "License" "Apache-2.0"
			(at 90.17 120.65 0)
			(effects
				(font
					(size 1.27 1.27)
					(thickness 0.15)
				)
				(justify left bottom)
				(hide yes)
			)
		)
		(property "Author" "Antmicro"
			(at 87.63 120.65 0)
			(effects
				(font
					(size 1.27 1.27)
					(thickness 0.15)
				)
				(justify left bottom)
				(hide yes)
			)
		)
		(property "Val" "2k2"
			(at 118.11 104.14 90)
			(effects
				(font
					(size 1.27 1.27)
					(thickness 0.15)
				)
				(justify left)
			)
		)
		(property "Tolerance" "1%"
			(at 105.41 120.65 0)
			(effects
				(font
					(size 1.27 1.27)
				)
				(justify left bottom)
				(hide yes)
			)
		)
		(pin "2"
		)
		(pin "1"
		)
		(instances
			(project "jetson-agx-thor-baseboard"
				(path ""
					(reference "R361")
					(unit 1)
				)
			)
		)
	)
	(symbol
		(lib_id "antmicropower:GND")
		(at 106.68 71.12 0)
		(unit 1)
		(exclude_from_sim no)
		(in_bom yes)
		(on_board yes)
		(dnp no)
		(property "Reference" "#PWR0151"
			(at 106.68 77.47 0)
			(effects
				(font
					(size 1.27 1.27)
				)
				(justify left bottom)
				(hide yes)
			)
		)
		(property "Value" "GND"
			(at 106.68 74.93 0)
			(effects
				(font
					(size 1.27 1.27)
					(thickness 0.15)
				)
			)
		)
		(property "Footprint" ""
			(at 115.57 78.74 0)
			(effects
				(font
					(size 1.27 1.27)
					(thickness 0.15)
				)
				(justify left bottom)
				(hide yes)
			)
		)
		(property "Datasheet" ""
			(at 115.57 83.82 0)
			(effects
				(font
					(size 1.27 1.27)
					(thickness 0.15)
				)
				(justify left bottom)
				(hide yes)
			)
		)
		(property "Description" ""
			(at 106.68 71.12 0)
			(effects
				(font
					(size 1.27 1.27)
				)
				(hide yes)
			)
		)
		(property "Author" "Antmicro"
			(at 115.57 78.74 0)
			(effects
				(font
					(size 1.27 1.27)
					(thickness 0.15)
				)
				(justify left bottom)
				(hide yes)
			)
		)
		(property "License" "Apache-2.0"
			(at 115.57 81.28 0)
			(effects
				(font
					(size 1.27 1.27)
					(thickness 0.15)
				)
				(justify left bottom)
				(hide yes)
			)
		)
		(pin "1"
		)
		(instances
			(project "jetson-agx-thor-baseboard"
				(path ""
					(reference "#PWR0151")
					(unit 1)
				)
			)
		)
	)
	(symbol
		(lib_id "antmicroResistors0402:R_2k2_0402")
		(at 135.89 100.33 270)
		(unit 1)
		(exclude_from_sim no)
		(in_bom yes)
		(on_board yes)
		(dnp no)
		(fields_autoplaced yes)
		(property "Reference" "R376"
			(at 138.43 101.6 90)
			(effects
				(font
					(size 1.27 1.27)
					(thickness 0.15)
				)
				(justify left)
			)
		)
		(property "Value" "R_2k2_0402"
			(at 123.19 120.65 0)
			(effects
				(font
					(size 1.27 1.27)
					(thickness 0.15)
				)
				(justify left bottom)
				(hide yes)
			)
		)
		(property "Footprint" "antmicro-footprints:R_0402_1005Metric"
			(at 120.65 120.65 0)
			(effects
				(font
					(size 1.27 1.27)
					(thickness 0.15)
				)
				(justify left bottom)
				(hide yes)
			)
		)
		(property "Datasheet" "https://www.bourns.com/docs/product-datasheets/cr.pdf"
			(at 118.11 120.65 0)
			(effects
				(font
					(size 1.27 1.27)
					(thickness 0.15)
				)
				(justify left bottom)
				(hide yes)
			)
		)
		(property "Description" "SMD Chip Resistor, 2.2 kohm, ± 1%, 62.5 mW, 0402 [1005 Metric], Thick Film, General Purpose"
			(at 105.41 120.65 0)
			(effects
				(font
					(size 1.27 1.27)
				)
				(justify left bottom)
				(hide yes)
			)
		)
		(property "MPN" "CR0402-FX-2201GLF"
			(at 115.57 120.65 0)
			(effects
				(font
					(size 1.27 1.27)
					(thickness 0.15)
				)
				(justify left bottom)
				(hide yes)
			)
		)
		(property "Manufacturer" "Bourns"
			(at 113.03 120.65 0)
			(effects
				(font
					(size 1.27 1.27)
					(thickness 0.15)
				)
				(justify left bottom)
				(hide yes)
			)
		)
		(property "License" "Apache-2.0"
			(at 110.49 120.65 0)
			(effects
				(font
					(size 1.27 1.27)
					(thickness 0.15)
				)
				(justify left bottom)
				(hide yes)
			)
		)
		(property "Author" "Antmicro"
			(at 107.95 120.65 0)
			(effects
				(font
					(size 1.27 1.27)
					(thickness 0.15)
				)
				(justify left bottom)
				(hide yes)
			)
		)
		(property "Val" "2k2"
			(at 138.43 104.14 90)
			(effects
				(font
					(size 1.27 1.27)
					(thickness 0.15)
				)
				(justify left)
			)
		)
		(property "Tolerance" "1%"
			(at 125.73 120.65 0)
			(effects
				(font
					(size 1.27 1.27)
				)
				(justify left bottom)
				(hide yes)
			)
		)
		(pin "2"
		)
		(pin "1"
		)
		(instances
			(project "jetson-agx-thor-baseboard"
				(path ""
					(reference "R376")
					(unit 1)
				)
			)
		)
	)
	(symbol
		(lib_id "antmicroResistors0402:R_2k2_0402")
		(at 52.07 50.8 270)
		(unit 1)
		(exclude_from_sim no)
		(in_bom no)
		(on_board yes)
		(dnp yes)
		(fields_autoplaced yes)
		(property "Reference" "R357"
			(at 54.61 52.07 90)
			(effects
				(font
					(size 1.27 1.27)
					(thickness 0.15)
				)
				(justify left)
			)
		)
		(property "Value" "R_2k2_0402"
			(at 39.37 71.12 0)
			(effects
				(font
					(size 1.27 1.27)
					(thickness 0.15)
				)
				(justify left bottom)
				(hide yes)
			)
		)
		(property "Footprint" "antmicro-footprints:R_0402_1005Metric"
			(at 36.83 71.12 0)
			(effects
				(font
					(size 1.27 1.27)
					(thickness 0.15)
				)
				(justify left bottom)
				(hide yes)
			)
		)
		(property "Datasheet" "https://www.bourns.com/docs/product-datasheets/cr.pdf"
			(at 34.29 71.12 0)
			(effects
				(font
					(size 1.27 1.27)
					(thickness 0.15)
				)
				(justify left bottom)
				(hide yes)
			)
		)
		(property "Description" "SMD Chip Resistor, 2.2 kohm, ± 1%, 62.5 mW, 0402 [1005 Metric], Thick Film, General Purpose"
			(at 21.59 71.12 0)
			(effects
				(font
					(size 1.27 1.27)
				)
				(justify left bottom)
				(hide yes)
			)
		)
		(property "MPN" "CR0402-FX-2201GLF"
			(at 31.75 71.12 0)
			(effects
				(font
					(size 1.27 1.27)
					(thickness 0.15)
				)
				(justify left bottom)
				(hide yes)
			)
		)
		(property "Manufacturer" "Bourns"
			(at 29.21 71.12 0)
			(effects
				(font
					(size 1.27 1.27)
					(thickness 0.15)
				)
				(justify left bottom)
				(hide yes)
			)
		)
		(property "License" "Apache-2.0"
			(at 26.67 71.12 0)
			(effects
				(font
					(size 1.27 1.27)
					(thickness 0.15)
				)
				(justify left bottom)
				(hide yes)
			)
		)
		(property "Author" "Antmicro"
			(at 24.13 71.12 0)
			(effects
				(font
					(size 1.27 1.27)
					(thickness 0.15)
				)
				(justify left bottom)
				(hide yes)
			)
		)
		(property "Val" "2k2"
			(at 54.61 54.61 90)
			(effects
				(font
					(size 1.27 1.27)
					(thickness 0.15)
				)
				(justify left)
			)
		)
		(property "Tolerance" "1%"
			(at 41.91 71.12 0)
			(effects
				(font
					(size 1.27 1.27)
				)
				(justify left bottom)
				(hide yes)
			)
		)
		(pin "2"
		)
		(pin "1"
		)
		(instances
			(project "jetson-agx-thor-baseboard"
				(path ""
					(reference "R357")
					(unit 1)
				)
			)
		)
	)
	(symbol
		(lib_id "antmicropower:GND")
		(at 113.03 210.82 0)
		(unit 1)
		(exclude_from_sim no)
		(in_bom yes)
		(on_board yes)
		(dnp no)
		(property "Reference" "#PWR0703"
			(at 113.03 217.17 0)
			(effects
				(font
					(size 1.27 1.27)
				)
				(justify left bottom)
				(hide yes)
			)
		)
		(property "Value" "GND"
			(at 113.03 214.63 0)
			(effects
				(font
					(size 1.27 1.27)
					(thickness 0.15)
				)
			)
		)
		(property "Footprint" ""
			(at 121.92 218.44 0)
			(effects
				(font
					(size 1.27 1.27)
					(thickness 0.15)
				)
				(justify left bottom)
				(hide yes)
			)
		)
		(property "Datasheet" ""
			(at 121.92 223.52 0)
			(effects
				(font
					(size 1.27 1.27)
					(thickness 0.15)
				)
				(justify left bottom)
				(hide yes)
			)
		)
		(property "Description" ""
			(at 113.03 210.82 0)
			(effects
				(font
					(size 1.27 1.27)
				)
				(hide yes)
			)
		)
		(property "Author" "Antmicro"
			(at 121.92 218.44 0)
			(effects
				(font
					(size 1.27 1.27)
					(thickness 0.15)
				)
				(justify left bottom)
				(hide yes)
			)
		)
		(property "License" "Apache-2.0"
			(at 121.92 220.98 0)
			(effects
				(font
					(size 1.27 1.27)
					(thickness 0.15)
				)
				(justify left bottom)
				(hide yes)
			)
		)
		(pin "1"
		)
		(instances
			(project "jetson-agx-thor-baseboard"
				(path ""
					(reference "#PWR0703")
					(unit 1)
				)
			)
		)
	)
	(symbol
		(lib_id "antmicropower:+1V8")
		(at 77.47 138.43 0)
		(unit 1)
		(exclude_from_sim no)
		(in_bom yes)
		(on_board yes)
		(dnp no)
		(property "Reference" "#PWR0702"
			(at 77.47 142.24 0)
			(effects
				(font
					(size 1.27 1.27)
				)
				(justify left bottom)
				(hide yes)
			)
		)
		(property "Value" "+1V8"
			(at 74.295 134.62 0)
			(effects
				(font
					(size 1.27 1.27)
					(thickness 0.15)
				)
				(justify left)
			)
		)
		(property "Footprint" ""
			(at 92.71 146.05 0)
			(effects
				(font
					(size 1.27 1.27)
					(thickness 0.15)
				)
				(justify left bottom)
				(hide yes)
			)
		)
		(property "Datasheet" ""
			(at 92.71 148.59 0)
			(effects
				(font
					(size 1.27 1.27)
					(thickness 0.15)
				)
				(justify left bottom)
				(hide yes)
			)
		)
		(property "Description" ""
			(at 77.47 138.43 0)
			(effects
				(font
					(size 1.27 1.27)
				)
				(hide yes)
			)
		)
		(property "Author" "Antmicro"
			(at 92.71 143.51 0)
			(effects
				(font
					(size 1.27 1.27)
					(thickness 0.15)
				)
				(justify left bottom)
				(hide yes)
			)
		)
		(property "License" "Apache-2.0"
			(at 92.71 146.05 0)
			(effects
				(font
					(size 1.27 1.27)
					(thickness 0.15)
				)
				(justify left bottom)
				(hide yes)
			)
		)
		(pin "1"
		)
		(instances
			(project "jetson-agx-thor-baseboard"
				(path ""
					(reference "#PWR0702")
					(unit 1)
				)
			)
		)
	)
	(symbol
		(lib_id "antmicroCapacitors0402:C_100n_0402")
		(at 90.17 40.64 270)
		(mirror x)
		(unit 1)
		(exclude_from_sim no)
		(in_bom yes)
		(on_board yes)
		(dnp no)
		(property "Reference" "C9"
			(at 88.265 36.83 90)
			(effects
				(font
					(size 1.27 1.27)
				)
				(justify right)
			)
		)
		(property "Value" "C_100n_0402"
			(at 80.01 20.32 0)
			(effects
				(font
					(size 1.27 1.27)
					(thickness 0.15)
				)
				(justify left bottom)
				(hide yes)
			)
		)
		(property "Footprint" "antmicro-footprints:C_0402_1005Metric"
			(at 77.47 20.32 0)
			(effects
				(font
					(size 1.27 1.27)
					(thickness 0.15)
				)
				(justify left bottom)
				(hide yes)
			)
		)
		(property "Datasheet" "https://www.murata.com/products/productdetail?partno=GRM155R61H104KE14%23"
			(at 74.93 20.32 0)
			(effects
				(font
					(size 1.27 1.27)
					(thickness 0.15)
				)
				(justify left bottom)
				(hide yes)
			)
		)
		(property "Description" "SMD Multilayer Ceramic Capacitor, 0.1 µF, 50 V, 0402 [1005 Metric], ± 10%, X5R, GRM Series"
			(at 90.17 40.64 0)
			(effects
				(font
					(size 1.27 1.27)
				)
				(hide yes)
			)
		)
		(property "Manufacturer" "Murata"
			(at 69.85 20.32 0)
			(effects
				(font
					(size 1.27 1.27)
					(thickness 0.15)
				)
				(justify left bottom)
				(hide yes)
			)
		)
		(property "MPN" "GRM155R61H104KE14D"
			(at 72.39 20.32 0)
			(effects
				(font
					(size 1.27 1.27)
					(thickness 0.15)
				)
				(justify left bottom)
				(hide yes)
			)
		)
		(property "Val" "100n"
			(at 88.265 39.37 90)
			(effects
				(font
					(size 1.27 1.27)
					(thickness 0.15)
				)
				(justify right)
			)
		)
		(property "License" "Apache-2.0"
			(at 67.31 20.32 0)
			(effects
				(font
					(size 1.27 1.27)
					(thickness 0.15)
				)
				(justify left bottom)
				(hide yes)
			)
		)
		(property "Author" "Antmicro"
			(at 64.77 20.32 0)
			(effects
				(font
					(size 1.27 1.27)
					(thickness 0.15)
				)
				(justify left bottom)
				(hide yes)
			)
		)
		(property "Voltage" "50V"
			(at 62.23 20.32 0)
			(effects
				(font
					(size 1.27 1.27)
				)
				(justify left bottom)
				(hide yes)
			)
		)
		(property "Dielectric" "X5R"
			(at 59.69 20.32 0)
			(effects
				(font
					(size 1.27 1.27)
				)
				(justify left bottom)
				(hide yes)
			)
		)
		(pin "1"
		)
		(pin "2"
		)
		(instances
			(project "jetson-agx-thor-baseboard"
				(path ""
					(reference "C9")
					(unit 1)
				)
			)
		)
	)
	(symbol
		(lib_id "antmicropower:+1V8")
		(at 90.17 85.09 0)
		(unit 1)
		(exclude_from_sim no)
		(in_bom yes)
		(on_board yes)
		(dnp no)
		(property "Reference" "#PWR02"
			(at 90.17 88.9 0)
			(effects
				(font
					(size 1.27 1.27)
				)
				(justify left bottom)
				(hide yes)
			)
		)
		(property "Value" "+1V8"
			(at 86.995 81.28 0)
			(effects
				(font
					(size 1.27 1.27)
					(thickness 0.15)
				)
				(justify left)
			)
		)
		(property "Footprint" ""
			(at 105.41 92.71 0)
			(effects
				(font
					(size 1.27 1.27)
					(thickness 0.15)
				)
				(justify left bottom)
				(hide yes)
			)
		)
		(property "Datasheet" ""
			(at 105.41 95.25 0)
			(effects
				(font
					(size 1.27 1.27)
					(thickness 0.15)
				)
				(justify left bottom)
				(hide yes)
			)
		)
		(property "Description" ""
			(at 90.17 85.09 0)
			(effects
				(font
					(size 1.27 1.27)
				)
				(hide yes)
			)
		)
		(property "Author" "Antmicro"
			(at 105.41 90.17 0)
			(effects
				(font
					(size 1.27 1.27)
					(thickness 0.15)
				)
				(justify left bottom)
				(hide yes)
			)
		)
		(property "License" "Apache-2.0"
			(at 105.41 92.71 0)
			(effects
				(font
					(size 1.27 1.27)
					(thickness 0.15)
				)
				(justify left bottom)
				(hide yes)
			)
		)
		(pin "1"
		)
		(instances
			(project "jetson-agx-thor-baseboard"
				(path ""
					(reference "#PWR02")
					(unit 1)
				)
			)
		)
	)
	(symbol
		(lib_id "antmicropower:+1V8")
		(at 80.01 181.61 0)
		(unit 1)
		(exclude_from_sim no)
		(in_bom yes)
		(on_board yes)
		(dnp no)
		(property "Reference" "#PWR0716"
			(at 80.01 185.42 0)
			(effects
				(font
					(size 1.27 1.27)
				)
				(justify left bottom)
				(hide yes)
			)
		)
		(property "Value" "+1V8"
			(at 76.835 177.8 0)
			(effects
				(font
					(size 1.27 1.27)
					(thickness 0.15)
				)
				(justify left)
			)
		)
		(property "Footprint" ""
			(at 95.25 189.23 0)
			(effects
				(font
					(size 1.27 1.27)
					(thickness 0.15)
				)
				(justify left bottom)
				(hide yes)
			)
		)
		(property "Datasheet" ""
			(at 95.25 191.77 0)
			(effects
				(font
					(size 1.27 1.27)
					(thickness 0.15)
				)
				(justify left bottom)
				(hide yes)
			)
		)
		(property "Description" ""
			(at 80.01 181.61 0)
			(effects
				(font
					(size 1.27 1.27)
				)
				(hide yes)
			)
		)
		(property "Author" "Antmicro"
			(at 95.25 186.69 0)
			(effects
				(font
					(size 1.27 1.27)
					(thickness 0.15)
				)
				(justify left bottom)
				(hide yes)
			)
		)
		(property "License" "Apache-2.0"
			(at 95.25 189.23 0)
			(effects
				(font
					(size 1.27 1.27)
					(thickness 0.15)
				)
				(justify left bottom)
				(hide yes)
			)
		)
		(pin "1"
		)
		(instances
			(project "jetson-agx-thor-baseboard"
				(path ""
					(reference "#PWR0716")
					(unit 1)
				)
			)
		)
	)
	(symbol
		(lib_id "antmicroResistors0402:R_2k2_0402")
		(at 52.07 101.6 270)
		(unit 1)
		(exclude_from_sim no)
		(in_bom no)
		(on_board yes)
		(dnp yes)
		(fields_autoplaced yes)
		(property "Reference" "R352"
			(at 54.61 102.87 90)
			(effects
				(font
					(size 1.27 1.27)
					(thickness 0.15)
				)
				(justify left)
			)
		)
		(property "Value" "R_2k2_0402"
			(at 39.37 121.92 0)
			(effects
				(font
					(size 1.27 1.27)
					(thickness 0.15)
				)
				(justify left bottom)
				(hide yes)
			)
		)
		(property "Footprint" "antmicro-footprints:R_0402_1005Metric"
			(at 36.83 121.92 0)
			(effects
				(font
					(size 1.27 1.27)
					(thickness 0.15)
				)
				(justify left bottom)
				(hide yes)
			)
		)
		(property "Datasheet" "https://www.bourns.com/docs/product-datasheets/cr.pdf"
			(at 34.29 121.92 0)
			(effects
				(font
					(size 1.27 1.27)
					(thickness 0.15)
				)
				(justify left bottom)
				(hide yes)
			)
		)
		(property "Description" "SMD Chip Resistor, 2.2 kohm, ± 1%, 62.5 mW, 0402 [1005 Metric], Thick Film, General Purpose"
			(at 21.59 121.92 0)
			(effects
				(font
					(size 1.27 1.27)
				)
				(justify left bottom)
				(hide yes)
			)
		)
		(property "MPN" "CR0402-FX-2201GLF"
			(at 31.75 121.92 0)
			(effects
				(font
					(size 1.27 1.27)
					(thickness 0.15)
				)
				(justify left bottom)
				(hide yes)
			)
		)
		(property "Manufacturer" "Bourns"
			(at 29.21 121.92 0)
			(effects
				(font
					(size 1.27 1.27)
					(thickness 0.15)
				)
				(justify left bottom)
				(hide yes)
			)
		)
		(property "License" "Apache-2.0"
			(at 26.67 121.92 0)
			(effects
				(font
					(size 1.27 1.27)
					(thickness 0.15)
				)
				(justify left bottom)
				(hide yes)
			)
		)
		(property "Author" "Antmicro"
			(at 24.13 121.92 0)
			(effects
				(font
					(size 1.27 1.27)
					(thickness 0.15)
				)
				(justify left bottom)
				(hide yes)
			)
		)
		(property "Val" "2k2"
			(at 54.61 105.41 90)
			(effects
				(font
					(size 1.27 1.27)
					(thickness 0.15)
				)
				(justify left)
			)
		)
		(property "Tolerance" "1%"
			(at 41.91 121.92 0)
			(effects
				(font
					(size 1.27 1.27)
				)
				(justify left bottom)
				(hide yes)
			)
		)
		(pin "2"
		)
		(pin "1"
		)
		(instances
			(project "jetson-agx-thor-baseboard"
				(path ""
					(reference "R352")
					(unit 1)
				)
			)
		)
	)
	(symbol
		(lib_id "antmicroTestPoints:TP_0.75mm_SMD")
		(at 307.34 217.17 0)
		(mirror y)
		(unit 1)
		(exclude_from_sim no)
		(in_bom no)
		(on_board yes)
		(dnp no)
		(property "Reference" "TP101"
			(at 303.022 217.17 0)
			(effects
				(font
					(size 1.27 1.27)
				)
				(justify left)
			)
		)
		(property "Value" "TP_0.75mm_SMD"
			(at 297.18 220.98 0)
			(effects
				(font
					(size 1.27 1.27)
					(thickness 0.15)
				)
				(justify left bottom)
				(hide yes)
			)
		)
		(property "Footprint" "antmicro-footprints:TP_SMD_0.75mm"
			(at 297.18 223.52 0)
			(effects
				(font
					(size 1.27 1.27)
					(thickness 0.15)
				)
				(justify left bottom)
				(hide yes)
			)
		)
		(property "Datasheet" ""
			(at 289.56 229.87 0)
			(effects
				(font
					(size 1.27 1.27)
					(thickness 0.15)
				)
				(justify left bottom)
				(hide yes)
			)
		)
		(property "Description" "SMT test point"
			(at 307.34 217.17 0)
			(effects
				(font
					(size 1.27 1.27)
				)
				(hide yes)
			)
		)
		(property "MPN" ""
			(at 296.545 228.6 0)
			(effects
				(font
					(size 1.27 1.27)
					(thickness 0.15)
				)
				(justify left bottom)
				(hide yes)
			)
		)
		(property "Manufacturer" ""
			(at 296.545 223.52 0)
			(effects
				(font
					(size 1.27 1.27)
					(thickness 0.15)
				)
				(justify left bottom)
				(hide yes)
			)
		)
		(property "Author" "Antmicro"
			(at 297.18 226.06 0)
			(effects
				(font
					(size 1.27 1.27)
					(thickness 0.15)
				)
				(justify left bottom)
				(hide yes)
			)
		)
		(property "License" "Apache-2.0"
			(at 297.18 228.6 0)
			(effects
				(font
					(size 1.27 1.27)
					(thickness 0.15)
				)
				(justify left bottom)
				(hide yes)
			)
		)
		(pin "1"
		)
		(instances
			(project "jetson-agx-thor-baseboard"
				(path ""
					(reference "TP101")
					(unit 1)
				)
			)
		)
	)
	(symbol
		(lib_id "antmicropower:GND")
		(at 90.17 41.91 0)
		(unit 1)
		(exclude_from_sim no)
		(in_bom yes)
		(on_board yes)
		(dnp no)
		(property "Reference" "#PWR024"
			(at 90.17 48.26 0)
			(effects
				(font
					(size 1.27 1.27)
				)
				(justify left bottom)
				(hide yes)
			)
		)
		(property "Value" "GND"
			(at 90.17 45.72 0)
			(effects
				(font
					(size 1.27 1.27)
					(thickness 0.15)
				)
			)
		)
		(property "Footprint" ""
			(at 99.06 49.53 0)
			(effects
				(font
					(size 1.27 1.27)
					(thickness 0.15)
				)
				(justify left bottom)
				(hide yes)
			)
		)
		(property "Datasheet" ""
			(at 99.06 54.61 0)
			(effects
				(font
					(size 1.27 1.27)
					(thickness 0.15)
				)
				(justify left bottom)
				(hide yes)
			)
		)
		(property "Description" ""
			(at 90.17 41.91 0)
			(effects
				(font
					(size 1.27 1.27)
				)
				(hide yes)
			)
		)
		(property "Author" "Antmicro"
			(at 99.06 49.53 0)
			(effects
				(font
					(size 1.27 1.27)
					(thickness 0.15)
				)
				(justify left bottom)
				(hide yes)
			)
		)
		(property "License" "Apache-2.0"
			(at 99.06 52.07 0)
			(effects
				(font
					(size 1.27 1.27)
					(thickness 0.15)
				)
				(justify left bottom)
				(hide yes)
			)
		)
		(pin "1"
		)
		(instances
			(project "jetson-agx-thor-baseboard"
				(path ""
					(reference "#PWR024")
					(unit 1)
				)
			)
		)
	)
	(symbol
		(lib_id "antmicroLogicTranslatorsLevelShifters:SN74AXC8T245_UQFN")
		(at 85.09 213.36 0)
		(unit 1)
		(exclude_from_sim no)
		(in_bom yes)
		(on_board yes)
		(dnp no)
		(fields_autoplaced yes)
		(property "Reference" "U5"
			(at 95.25 205.74 0)
			(effects
				(font
					(size 1.27 1.27)
					(thickness 0.15)
				)
			)
		)
		(property "Value" "SN74AXC8T245_UQFN"
			(at 135.89 218.44 0)
			(effects
				(font
					(size 1.27 1.27)
					(thickness 0.15)
				)
				(justify left bottom)
				(hide yes)
			)
		)
		(property "Footprint" "antmicro-footprints:UQFN-24_2x4mm_P0.4mm_Texas_RJW0024A"
			(at 135.89 223.52 0)
			(effects
				(font
					(size 1.27 1.27)
					(thickness 0.15)
				)
				(justify left bottom)
				(hide yes)
			)
		)
		(property "Datasheet" "https://www.ti.com/lit/ds/symlink/sn74axc8t245.pdf?ts=1702327536011"
			(at 135.89 226.06 0)
			(effects
				(font
					(size 1.27 1.27)
					(thickness 0.15)
				)
				(justify left bottom)
				(hide yes)
			)
		)
		(property "Description" "8-bit dual-supply bus transceiver"
			(at 135.89 233.68 0)
			(effects
				(font
					(size 1.27 1.27)
				)
				(justify left bottom)
				(hide yes)
			)
		)
		(property "MPN" "SN74AXC8T245RJWR"
			(at 95.25 208.28 0)
			(effects
				(font
					(size 1.27 1.27)
				)
			)
		)
		(property "Manufacturer" "Texas Instruments"
			(at 135.89 220.98 0)
			(effects
				(font
					(size 1.27 1.27)
				)
				(justify left bottom)
				(hide yes)
			)
		)
		(property "Author" "Antmicro"
			(at 135.89 228.6 0)
			(effects
				(font
					(size 1.27 1.27)
					(thickness 0.15)
				)
				(justify left bottom)
				(hide yes)
			)
		)
		(property "License" "Apache-2.0"
			(at 135.89 231.14 0)
			(effects
				(font
					(size 1.27 1.27)
					(thickness 0.15)
				)
				(justify left bottom)
				(hide yes)
			)
		)
		(pin "20"
		)
		(pin "8"
		)
		(pin "23"
		)
		(pin "7"
		)
		(pin "13"
		)
		(pin "16"
		)
		(pin "6"
		)
		(pin "11"
		)
		(pin "18"
		)
		(pin "15"
		)
		(pin "17"
		)
		(pin "19"
		)
		(pin "1"
		)
		(pin "14"
		)
		(pin "5"
		)
		(pin "10"
		)
		(pin "2"
		)
		(pin "22"
		)
		(pin "24"
		)
		(pin "3"
		)
		(pin "12"
		)
		(pin "4"
		)
		(pin "9"
		)
		(pin "21"
		)
		(instances
			(project "jetson-agx-thor-baseboard"
				(path ""
					(reference "U5")
					(unit 1)
				)
			)
		)
	)
	(symbol
		(lib_id "antmicroLogicTranslatorsLevelShifters:NTS0104_DHVQFN")
		(at 85.09 105.41 0)
		(unit 1)
		(exclude_from_sim no)
		(in_bom yes)
		(on_board yes)
		(dnp no)
		(property "Reference" "U80"
			(at 95.25 99.06 0)
			(effects
				(font
					(size 1.27 1.27)
					(thickness 0.15)
				)
			)
		)
		(property "Value" "NTS0104_DHVQFN"
			(at 120.65 113.03 0)
			(effects
				(font
					(size 1.27 1.27)
					(thickness 0.15)
				)
				(justify left bottom)
				(hide yes)
			)
		)
		(property "Footprint" "antmicro-footprints:DHVQFN-14-1EP_2.5x3mm"
			(at 120.65 115.57 0)
			(effects
				(font
					(size 1.27 1.27)
					(thickness 0.15)
				)
				(justify left bottom)
				(hide yes)
			)
		)
		(property "Datasheet" "https://www.nxp.com/docs/en/data-sheet/NTS0104.pdf"
			(at 120.65 118.11 0)
			(effects
				(font
					(size 1.27 1.27)
					(thickness 0.15)
				)
				(justify left bottom)
				(hide yes)
			)
		)
		(property "Description" "Voltage Level Translator Bidirectional 1 Circuit 4 Channel 50Mbps 14-DHVQFN (2.5x3)"
			(at 120.65 128.27 0)
			(effects
				(font
					(size 1.27 1.27)
				)
				(justify left bottom)
				(hide yes)
			)
		)
		(property "MPN" "NTS0104BQ"
			(at 95.25 101.6 0)
			(effects
				(font
					(size 1.27 1.27)
					(thickness 0.15)
				)
			)
		)
		(property "Manufacturer" "NXP"
			(at 120.65 120.65 0)
			(effects
				(font
					(size 1.27 1.27)
					(thickness 0.15)
				)
				(justify left bottom)
				(hide yes)
			)
		)
		(property "Author" "Antmicro"
			(at 120.65 123.19 0)
			(effects
				(font
					(size 1.27 1.27)
					(thickness 0.15)
				)
				(justify left bottom)
				(hide yes)
			)
		)
		(property "License" "Apache-2.0"
			(at 120.65 125.73 0)
			(effects
				(font
					(size 1.27 1.27)
					(thickness 0.15)
				)
				(justify left bottom)
				(hide yes)
			)
		)
		(pin "9"
		)
		(pin "7"
		)
		(pin "10"
		)
		(pin "11"
		)
		(pin "6"
		)
		(pin "12"
		)
		(pin "15"
		)
		(pin "13"
		)
		(pin "5"
		)
		(pin "4"
		)
		(pin "3"
		)
		(pin "2"
		)
		(pin "8"
		)
		(pin "1"
		)
		(pin "14"
		)
		(instances
			(project "jetson-agx-thor-baseboard"
				(path ""
					(reference "U80")
					(unit 1)
				)
			)
		)
	)
	(symbol
		(lib_id "antmicropower:+3V3")
		(at 130.81 44.45 0)
		(unit 1)
		(exclude_from_sim no)
		(in_bom yes)
		(on_board yes)
		(dnp no)
		(property "Reference" "#PWR0761"
			(at 130.81 48.26 0)
			(effects
				(font
					(size 1.27 1.27)
				)
				(justify left bottom)
				(hide yes)
			)
		)
		(property "Value" "+3V3"
			(at 127.635 40.64 0)
			(effects
				(font
					(size 1.27 1.27)
					(thickness 0.15)
				)
				(justify left)
			)
		)
		(property "Footprint" ""
			(at 146.05 52.07 0)
			(effects
				(font
					(size 1.27 1.27)
					(thickness 0.15)
				)
				(justify left bottom)
				(hide yes)
			)
		)
		(property "Datasheet" ""
			(at 146.05 54.61 0)
			(effects
				(font
					(size 1.27 1.27)
					(thickness 0.15)
				)
				(justify left bottom)
				(hide yes)
			)
		)
		(property "Description" ""
			(at 130.81 44.45 0)
			(effects
				(font
					(size 1.27 1.27)
				)
				(hide yes)
			)
		)
		(property "Author" "Antmicro"
			(at 146.05 46.99 0)
			(effects
				(font
					(size 1.27 1.27)
					(thickness 0.15)
				)
				(justify left bottom)
				(hide yes)
			)
		)
		(property "License" "Apache-2.0"
			(at 146.05 49.53 0)
			(effects
				(font
					(size 1.27 1.27)
					(thickness 0.15)
				)
				(justify left bottom)
				(hide yes)
			)
		)
		(pin "1"
		)
		(instances
			(project "jetson-agx-thor-baseboard"
				(path ""
					(reference "#PWR0761")
					(unit 1)
				)
			)
		)
	)
	(symbol
		(lib_id "antmicroB2BConnectors:Hermaphroditic_Molex_203456-0003_CUSTOM_Jetson_AGX_Thor_H8mm")
		(at 321.31 152.4 0)
		(unit 4)
		(exclude_from_sim no)
		(in_bom yes)
		(on_board yes)
		(dnp no)
		(fields_autoplaced yes)
		(property "Reference" "J1"
			(at 342.9 144.78 0)
			(effects
				(font
					(size 1.27 1.27)
				)
			)
		)
		(property "Value" "Hermaphroditic_Molex_203456-0003_CUSTOM_Jetson_AGX_Thor_H8mm"
			(at 397.764 158.496 0)
			(effects
				(font
					(size 1.27 1.27)
				)
				(justify left bottom)
				(hide yes)
			)
		)
		(property "Footprint" "antmicro-footprints:Conn_Hermaphroditic_Molex_203456-0003_mirrored"
			(at 397.764 160.782 0)
			(effects
				(font
					(size 1.27 1.27)
				)
				(justify left bottom)
				(hide yes)
			)
		)
		(property "Datasheet" "https://www.molex.com/content/dam/molex/molex-dot-com/products/automated/en-us/salesdrawingpdf/203/203456/2034560003_sd.pdf?inline"
			(at 397.764 163.068 0)
			(effects
				(font
					(size 1.27 1.27)
				)
				(justify left bottom)
				(hide yes)
			)
		)
		(property "Description" "Mirror Mezz Hermaphroditic Connector, 5.50mm Connector Height, BGA-Attach Mounting, 7 Pair, 11 Row, 699 Circuits, 0.76µm Gold Plating, without Pegs"
			(at 397.764 171.704 0)
			(effects
				(font
					(size 1.27 1.27)
				)
				(justify left bottom)
				(hide yes)
			)
		)
		(property "MPN" "203456-0003"
			(at 342.9 147.32 0)
			(effects
				(font
					(size 1.27 1.27)
				)
			)
		)
		(property "Manufacturer" "Molex"
			(at 397.764 165.354 0)
			(effects
				(font
					(size 1.27 1.27)
				)
				(justify left bottom)
				(hide yes)
			)
		)
		(property "Author" "Antmicro"
			(at 397.764 167.386 0)
			(effects
				(font
					(size 1.27 1.27)
				)
				(justify left bottom)
				(hide yes)
			)
		)
		(property "License" "Apache-2.0"
			(at 397.764 169.418 0)
			(effects
				(font
					(size 1.27 1.27)
				)
				(justify left bottom)
				(hide yes)
			)
		)
		(pin "L27"
		)
		(pin "A33"
		)
		(pin "J65"
		)
		(pin "A29"
		)
		(pin "D63"
		)
		(pin "G2"
		)
		(pin "J64"
		)
		(pin "F65"
		)
		(pin "D64"
		)
		(pin "L22"
		)
		(pin "D2"
		)
		(pin "G33"
		)
		(pin "F3"
		)
		(pin "H64"
		)
		(pin "H3"
		)
		(pin "G65"
		)
		(pin "F1"
		)
		(pin "J63"
		)
		(pin "D65"
		)
		(pin "B44"
		)
		(pin "F11"
		)
		(pin "B39"
		)
		(pin "E36"
		)
		(pin "B11"
		)
		(pin "D57"
		)
		(pin "E21"
		)
		(pin "E28"
		)
		(pin "E24"
		)
		(pin "E12"
		)
		(pin "C9"
		)
		(pin "D39"
		)
		(pin "E65"
		)
		(pin "H1"
		)
		(pin "D3"
		)
		(pin "H2"
		)
		(pin "F51"
		)
		(pin "A55"
		)
		(pin "J2"
		)
		(pin "F63"
		)
		(pin "L55"
		)
		(pin "B19"
		)
		(pin "B38"
		)
		(pin "E32"
		)
		(pin "G36"
		)
		(pin "E37"
		)
		(pin "E64"
		)
		(pin "L23"
		)
		(pin "A46"
		)
		(pin "H65"
		)
		(pin "C55"
		)
		(pin "B53"
		)
		(pin "C13"
		)
		(pin "C34"
		)
		(pin "C35"
		)
		(pin "F19"
		)
		(pin "L47"
		)
		(pin "C63"
		)
		(pin "E46"
		)
		(pin "C29"
		)
		(pin "H31"
		)
		(pin "D37"
		)
		(pin "H41"
		)
		(pin "J32"
		)
		(pin "G5"
		)
		(pin "B55"
		)
		(pin "L60"
		)
		(pin "B10"
		)
		(pin "K52"
		)
		(pin "K51"
		)
		(pin "E6"
		)
		(pin "F44"
		)
		(pin "C23"
		)
		(pin "C22"
		)
		(pin "L42"
		)
		(pin "E29"
		)
		(pin "A16"
		)
		(pin "E16"
		)
		(pin "D7"
		)
		(pin "K15"
		)
		(pin "L31"
		)
		(pin "G62"
		)
		(pin "F6"
		)
		(pin "H16"
		)
		(pin "G18"
		)
		(pin "F4"
		)
		(pin "C12"
		)
		(pin "K31"
		)
		(pin "B7"
		)
		(pin "B57"
		)
		(pin "E2"
		)
		(pin "F14"
		)
		(pin "A9"
		)
		(pin "E52"
		)
		(pin "H56"
		)
		(pin "A37"
		)
		(pin "D34"
		)
		(pin "E62"
		)
		(pin "H34"
		)
		(pin "D41"
		)
		(pin "F15"
		)
		(pin "A32"
		)
		(pin "B35"
		)
		(pin "D4"
		)
		(pin "D26"
		)
		(pin "G13"
		)
		(pin "B41"
		)
		(pin "B30"
		)
		(pin "F23"
		)
		(pin "A12"
		)
		(pin "L20"
		)
		(pin "J29"
		)
		(pin "G63"
		)
		(pin "A22"
		)
		(pin "A23"
		)
		(pin "H35"
		)
		(pin "K34"
		)
		(pin "L13"
		)
		(pin "K35"
		)
		(pin "J3"
		)
		(pin "C49"
		)
		(pin "L53"
		)
		(pin "J36"
		)
		(pin "D15"
		)
		(pin "E33"
		)
		(pin "G32"
		)
		(pin "A63"
		)
		(pin "L12"
		)
		(pin "B50"
		)
		(pin "C33"
		)
		(pin "D38"
		)
		(pin "G29"
		)
		(pin "L51"
		)
		(pin "H54"
		)
		(pin "K53"
		)
		(pin "K54"
		)
		(pin "L61"
		)
		(pin "L58"
		)
		(pin "G3"
		)
		(pin "G43"
		)
		(pin "C28"
		)
		(pin "L8"
		)
		(pin "J61"
		)
		(pin "D40"
		)
		(pin "B40"
		)
		(pin "K36"
		)
		(pin "D44"
		)
		(pin "F27"
		)
		(pin "D53"
		)
		(pin "K19"
		)
		(pin "J57"
		)
		(pin "A56"
		)
		(pin "D55"
		)
		(pin "K8"
		)
		(pin "L16"
		)
		(pin "J12"
		)
		(pin "D23"
		)
		(pin "F34"
		)
		(pin "H4"
		)
		(pin "F54"
		)
		(pin "G55"
		)
		(pin "K7"
		)
		(pin "H9"
		)
		(pin "L14"
		)
		(pin "G39"
		)
		(pin "G38"
		)
		(pin "H36"
		)
		(pin "H37"
		)
		(pin "K40"
		)
		(pin "K45"
		)
		(pin "F10"
		)
		(pin "F9"
		)
		(pin "C39"
		)
		(pin "A58"
		)
		(pin "F49"
		)
		(pin "G48"
		)
		(pin "G47"
		)
		(pin "K42"
		)
		(pin "G23"
		)
		(pin "G22"
		)
		(pin "H10"
		)
		(pin "L18"
		)
		(pin "L26"
		)
		(pin "L34"
		)
		(pin "G37"
		)
		(pin "H60"
		)
		(pin "C61"
		)
		(pin "A62"
		)
		(pin "G7"
		)
		(pin "L15"
		)
		(pin "J56"
		)
		(pin "F26"
		)
		(pin "H15"
		)
		(pin "H40"
		)
		(pin "J20"
		)
		(pin "F7"
		)
		(pin "D8"
		)
		(pin "C7"
		)
		(pin "H8"
		)
		(pin "L9"
		)
		(pin "L48"
		)
		(pin "J54"
		)
		(pin "J28"
		)
		(pin "B16"
		)
		(pin "B17"
		)
		(pin "K39"
		)
		(pin "B51"
		)
		(pin "B52"
		)
		(pin "A13"
		)
		(pin "E3"
		)
		(pin "B14"
		)
		(pin "B42"
		)
		(pin "A41"
		)
		(pin "A42"
		)
		(pin "D22"
		)
		(pin "G15"
		)
		(pin "G14"
		)
		(pin "A52"
		)
		(pin "C21"
		)
		(pin "G52"
		)
		(pin "K62"
		)
		(pin "E58"
		)
		(pin "B60"
		)
		(pin "A60"
		)
		(pin "J21"
		)
		(pin "K22"
		)
		(pin "J4"
		)
		(pin "B59"
		)
		(pin "A59"
		)
		(pin "B62"
		)
		(pin "H32"
		)
		(pin "H33"
		)
		(pin "K50"
		)
		(pin "D19"
		)
		(pin "H28"
		)
		(pin "H29"
		)
		(pin "B34"
		)
		(pin "H22"
		)
		(pin "H49"
		)
		(pin "H48"
		)
		(pin "L36"
		)
		(pin "L37"
		)
		(pin "J37"
		)
		(pin "F30"
		)
		(pin "H24"
		)
		(pin "H25"
		)
		(pin "A3"
		)
		(pin "G4"
		)
		(pin "E4"
		)
		(pin "F5"
		)
		(pin "G51"
		)
		(pin "G50"
		)
		(pin "B47"
		)
		(pin "C16"
		)
		(pin "G40"
		)
		(pin "C43"
		)
		(pin "J34"
		)
		(pin "A34"
		)
		(pin "A35"
		)
		(pin "L30"
		)
		(pin "B27"
		)
		(pin "G64"
		)
		(pin "K23"
		)
		(pin "G17"
		)
		(pin "F16"
		)
		(pin "F17"
		)
		(pin "H19"
		)
		(pin "G12"
		)
		(pin "B12"
		)
		(pin "B13"
		)
		(pin "J24"
		)
		(pin "E9"
		)
		(pin "L17"
		)
		(pin "L32"
		)
		(pin "L33"
		)
		(pin "F32"
		)
		(pin "F33"
		)
		(pin "K38"
		)
		(pin "E63"
		)
		(pin "F64"
		)
		(pin "E1"
		)
		(pin "G24"
		)
		(pin "D1"
		)
		(pin "F18"
		)
		(pin "H51"
		)
		(pin "J52"
		)
		(pin "F39"
		)
		(pin "J43"
		)
		(pin "E15"
		)
		(pin "E14"
		)
		(pin "L24"
		)
		(pin "H5"
		)
		(pin "K6"
		)
		(pin "J5"
		)
		(pin "J6"
		)
		(pin "L59"
		)
		(pin "K3"
		)
		(pin "D28"
		)
		(pin "D29"
		)
		(pin "C25"
		)
		(pin "A15"
		)
		(pin "A14"
		)
		(pin "K30"
		)
		(pin "D35"
		)
		(pin "J46"
		)
		(pin "F57"
		)
		(pin "F42"
		)
		(pin "E42"
		)
		(pin "E41"
		)
		(pin "A24"
		)
		(pin "C46"
		)
		(pin "J60"
		)
		(pin "F61"
		)
		(pin "H27"
		)
		(pin "B18"
		)
		(pin "A43"
		)
		(pin "D27"
		)
		(pin "H14"
		)
		(pin "A17"
		)
		(pin "F24"
		)
		(pin "F25"
		)
		(pin "A51"
		)
		(pin "A50"
		)
		(pin "C51"
		)
		(pin "C50"
		)
		(pin "C1"
		)
		(pin "J22"
		)
		(pin "J23"
		)
		(pin "C2"
		)
		(pin "B3"
		)
		(pin "G35"
		)
		(pin "G34"
		)
		(pin "B63"
		)
		(pin "A28"
		)
		(pin "B31"
		)
		(pin "C64"
		)
		(pin "C60"
		)
		(pin "K59"
		)
		(pin "J59"
		)
		(pin "C42"
		)
		(pin "C41"
		)
		(pin "F46"
		)
		(pin "K26"
		)
		(pin "D49"
		)
		(pin "D48"
		)
		(pin "G58"
		)
		(pin "A57"
		)
		(pin "C58"
		)
		(pin "C56"
		)
		(pin "D46"
		)
		(pin "D45"
		)
		(pin "J44"
		)
		(pin "K46"
		)
		(pin "K47"
		)
		(pin "J47"
		)
		(pin "J48"
		)
		(pin "D14"
		)
		(pin "F20"
		)
		(pin "F21"
		)
		(pin "F43"
		)
		(pin "J62"
		)
		(pin "B21"
		)
		(pin "B20"
		)
		(pin "E47"
		)
		(pin "E48"
		)
		(pin "C44"
		)
		(pin "H17"
		)
		(pin "G19"
		)
		(pin "C59"
		)
		(pin "F60"
		)
		(pin "C57"
		)
		(pin "E56"
		)
		(pin "J53"
		)
		(pin "K5"
		)
		(pin "G31"
		)
		(pin "G30"
		)
		(pin "D11"
		)
		(pin "H44"
		)
		(pin "L46"
		)
		(pin "L7"
		)
		(pin "L25"
		)
		(pin "B23"
		)
		(pin "F58"
		)
		(pin "D59"
		)
		(pin "B61"
		)
		(pin "H61"
		)
		(pin "J41"
		)
		(pin "J42"
		)
		(pin "B43"
		)
		(pin "B29"
		)
		(pin "B28"
		)
		(pin "D51"
		)
		(pin "D52"
		)
		(pin "F62"
		)
		(pin "E51"
		)
		(pin "E50"
		)
		(pin "K56"
		)
		(pin "K55"
		)
		(pin "F45"
		)
		(pin "E45"
		)
		(pin "E44"
		)
		(pin "A8"
		)
		(pin "K49"
		)
		(pin "K21"
		)
		(pin "K20"
		)
		(pin "E13"
		)
		(pin "C52"
		)
		(pin "H26"
		)
		(pin "J49"
		)
		(pin "D47"
		)
		(pin "B25"
		)
		(pin "B24"
		)
		(pin "L28"
		)
		(pin "K4"
		)
		(pin "D20"
		)
		(pin "D21"
		)
		(pin "E25"
		)
		(pin "G20"
		)
		(pin "H42"
		)
		(pin "G41"
		)
		(pin "G42"
		)
		(pin "L10"
		)
		(pin "L11"
		)
		(pin "H23"
		)
		(pin "B37"
		)
		(pin "E11"
		)
		(pin "H63"
		)
		(pin "E34"
		)
		(pin "F37"
		)
		(pin "F36"
		)
		(pin "E35"
		)
		(pin "E7"
		)
		(pin "F8"
		)
		(pin "A4"
		)
		(pin "J26"
		)
		(pin "J27"
		)
		(pin "L35"
		)
		(pin "J11"
		)
		(pin "E27"
		)
		(pin "A21"
		)
		(pin "K18"
		)
		(pin "B33"
		)
		(pin "B32"
		)
		(pin "E60"
		)
		(pin "A53"
		)
		(pin "E23"
		)
		(pin "E22"
		)
		(pin "D50"
		)
		(pin "G57"
		)
		(pin "C53"
		)
		(pin "K10"
		)
		(pin "F22"
		)
		(pin "H20"
		)
		(pin "H21"
		)
		(pin "G11"
		)
		(pin "G10"
		)
		(pin "B26"
		)
		(pin "J16"
		)
		(pin "J40"
		)
		(pin "K14"
		)
		(pin "G8"
		)
		(pin "C8"
		)
		(pin "B58"
		)
		(pin "H52"
		)
		(pin "C38"
		)
		(pin "A18"
		)
		(pin "G49"
		)
		(pin "J55"
		)
		(pin "A47"
		)
		(pin "A40"
		)
		(pin "L52"
		)
		(pin "A6"
		)
		(pin "J13"
		)
		(pin "B22"
		)
		(pin "G16"
		)
		(pin "F38"
		)
		(pin "F2"
		)
		(pin "F50"
		)
		(pin "H7"
		)
		(pin "F35"
		)
		(pin "G1"
		)
		(pin "K13"
		)
		(pin "K12"
		)
		(pin "G46"
		)
		(pin "J58"
		)
		(pin "H58"
		)
		(pin "K57"
		)
		(pin "E54"
		)
		(pin "G21"
		)
		(pin "D16"
		)
		(pin "D17"
		)
		(pin "A19"
		)
		(pin "A38"
		)
		(pin "E5"
		)
		(pin "B54"
		)
		(pin "A54"
		)
		(pin "E39"
		)
		(pin "E38"
		)
		(pin "H43"
		)
		(pin "K17"
		)
		(pin "K16"
		)
		(pin "J45"
		)
		(pin "K44"
		)
		(pin "K43"
		)
		(pin "D58"
		)
		(pin "G61"
		)
		(pin "H59"
		)
		(pin "G60"
		)
		(pin "F41"
		)
		(pin "H11"
		)
		(pin "C6"
		)
		(pin "G59"
		)
		(pin "E53"
		)
		(pin "D61"
		)
		(pin "L56"
		)
		(pin "A61"
		)
		(pin "C31"
		)
		(pin "C30"
		)
		(pin "K41"
		)
		(pin "K63"
		)
		(pin "H47"
		)
		(pin "D18"
		)
		(pin "L54"
		)
		(pin "L62"
		)
		(pin "K11"
		)
		(pin "G27"
		)
		(pin "G26"
		)
		(pin "D10"
		)
		(pin "J9"
		)
		(pin "C20"
		)
		(pin "L19"
		)
		(pin "B36"
		)
		(pin "L39"
		)
		(pin "C62"
		)
		(pin "C17"
		)
		(pin "C32"
		)
		(pin "A48"
		)
		(pin "H55"
		)
		(pin "B8"
		)
		(pin "L50"
		)
		(pin "L49"
		)
		(pin "F31"
		)
		(pin "H62"
		)
		(pin "K60"
		)
		(pin "L4"
		)
		(pin "L6"
		)
		(pin "C54"
		)
		(pin "D54"
		)
		(pin "J51"
		)
		(pin "J33"
		)
		(pin "F56"
		)
		(pin "A39"
		)
		(pin "E59"
		)
		(pin "F59"
		)
		(pin "L57"
		)
		(pin "L44"
		)
		(pin "F12"
		)
		(pin "F13"
		)
		(pin "D30"
		)
		(pin "C45"
		)
		(pin "D42"
		)
		(pin "D43"
		)
		(pin "A25"
		)
		(pin "H38"
		)
		(pin "K37"
		)
		(pin "L41"
		)
		(pin "C37"
		)
		(pin "G28"
		)
		(pin "E43"
		)
		(pin "J1"
		)
		(pin "J17"
		)
		(pin "D33"
		)
		(pin "D32"
		)
		(pin "J35"
		)
		(pin "H18"
		)
		(pin "E20"
		)
		(pin "L5"
		)
		(pin "H6"
		)
		(pin "K58"
		)
		(pin "H57"
		)
		(pin "B15"
		)
		(pin "J38"
		)
		(pin "J39"
		)
		(pin "D36"
		)
		(pin "H50"
		)
		(pin "B48"
		)
		(pin "B49"
		)
		(pin "B9"
		)
		(pin "F47"
		)
		(pin "E57"
		)
		(pin "D31"
		)
		(pin "E30"
		)
		(pin "D9"
		)
		(pin "B5"
		)
		(pin "E49"
		)
		(pin "C3"
		)
		(pin "A30"
		)
		(pin "A31"
		)
		(pin "E19"
		)
		(pin "E18"
		)
		(pin "C19"
		)
		(pin "C36"
		)
		(pin "K48"
		)
		(pin "J10"
		)
		(pin "K9"
		)
		(pin "E31"
		)
		(pin "F55"
		)
		(pin "D56"
		)
		(pin "G56"
		)
		(pin "G44"
		)
		(pin "G45"
		)
		(pin "F48"
		)
		(pin "J7"
		)
		(pin "J19"
		)
		(pin "C47"
		)
		(pin "C48"
		)
		(pin "F40"
		)
		(pin "D24"
		)
		(pin "D25"
		)
		(pin "K61"
		)
		(pin "F53"
		)
		(pin "D60"
		)
		(pin "E61"
		)
		(pin "D62"
		)
		(pin "L40"
		)
		(pin "L43"
		)
		(pin "L63"
		)
		(pin "K27"
		)
		(pin "B46"
		)
		(pin "A44"
		)
		(pin "A45"
		)
		(pin "B4"
		)
		(pin "G25"
		)
		(pin "L29"
		)
		(pin "L3"
		)
		(pin "K25"
		)
		(pin "K24"
		)
		(pin "A26"
		)
		(pin "A27"
		)
		(pin "H39"
		)
		(pin "E17"
		)
		(pin "G9"
		)
		(pin "C4"
		)
		(pin "D5"
		)
		(pin "G6"
		)
		(pin "J18"
		)
		(pin "E26"
		)
		(pin "F52"
		)
		(pin "H12"
		)
		(pin "H13"
		)
		(pin "A10"
		)
		(pin "A11"
		)
		(pin "K29"
		)
		(pin "K28"
		)
		(pin "A7"
		)
		(pin "E10"
		)
		(pin "C5"
		)
		(pin "D6"
		)
		(pin "B6"
		)
		(pin "A5"
		)
		(pin "E8"
		)
		(pin "A49"
		)
		(pin "A36"
		)
		(pin "H46"
		)
		(pin "H45"
		)
		(pin "B45"
		)
		(pin "J30"
		)
		(pin "J31"
		)
		(pin "C15"
		)
		(pin "C14"
		)
		(pin "J14"
		)
		(pin "J15"
		)
		(pin "C27"
		)
		(pin "C26"
		)
		(pin "K32"
		)
		(pin "K33"
		)
		(pin "J8"
		)
		(pin "J25"
		)
		(pin "L38"
		)
		(pin "C40"
		)
		(pin "D12"
		)
		(pin "D13"
		)
		(pin "A20"
		)
		(pin "H30"
		)
		(pin "E40"
		)
		(pin "L21"
		)
		(pin "H53"
		)
		(pin "E55"
		)
		(pin "B56"
		)
		(pin "F28"
		)
		(pin "F29"
		)
		(pin "C11"
		)
		(pin "C10"
		)
		(pin "L45"
		)
		(pin "J50"
		)
		(pin "C65"
		)
		(pin "G53"
		)
		(pin "G54"
		)
		(pin "C18"
		)
		(pin "C24"
		)
		(instances
			(project ""
				(path ""
					(reference "J1")
					(unit 4)
				)
			)
		)
	)
	(symbol
		(lib_id "antmicroTestPoints:TP_0.75mm_SMD")
		(at 311.15 247.65 180)
		(unit 1)
		(exclude_from_sim no)
		(in_bom no)
		(on_board yes)
		(dnp no)
		(property "Reference" "TP74"
			(at 307.34 247.65 0)
			(effects
				(font
					(size 1.27 1.27)
				)
				(justify left)
			)
		)
		(property "Value" "TP_0.75mm_SMD"
			(at 300.99 243.84 0)
			(effects
				(font
					(size 1.27 1.27)
					(thickness 0.15)
				)
				(justify left bottom)
				(hide yes)
			)
		)
		(property "Footprint" "antmicro-footprints:TP_SMD_0.75mm"
			(at 300.99 241.3 0)
			(effects
				(font
					(size 1.27 1.27)
					(thickness 0.15)
				)
				(justify left bottom)
				(hide yes)
			)
		)
		(property "Datasheet" ""
			(at 293.37 234.95 0)
			(effects
				(font
					(size 1.27 1.27)
					(thickness 0.15)
				)
				(justify left bottom)
				(hide yes)
			)
		)
		(property "Description" "SMT test point"
			(at 311.15 247.65 0)
			(effects
				(font
					(size 1.27 1.27)
				)
				(hide yes)
			)
		)
		(property "MPN" ""
			(at 300.355 236.22 0)
			(effects
				(font
					(size 1.27 1.27)
					(thickness 0.15)
				)
				(justify left bottom)
				(hide yes)
			)
		)
		(property "Manufacturer" ""
			(at 300.355 241.3 0)
			(effects
				(font
					(size 1.27 1.27)
					(thickness 0.15)
				)
				(justify left bottom)
				(hide yes)
			)
		)
		(property "Author" "Antmicro"
			(at 300.99 238.76 0)
			(effects
				(font
					(size 1.27 1.27)
					(thickness 0.15)
				)
				(justify left bottom)
				(hide yes)
			)
		)
		(property "License" "Apache-2.0"
			(at 300.99 236.22 0)
			(effects
				(font
					(size 1.27 1.27)
					(thickness 0.15)
				)
				(justify left bottom)
				(hide yes)
			)
		)
		(pin "1"
		)
		(instances
			(project "jetson-agx-thor-baseboard"
				(path ""
					(reference "TP74")
					(unit 1)
				)
			)
		)
	)
	(symbol
		(lib_id "antmicropower:GND")
		(at 90.17 92.71 0)
		(unit 1)
		(exclude_from_sim no)
		(in_bom yes)
		(on_board yes)
		(dnp no)
		(property "Reference" "#PWR03"
			(at 90.17 99.06 0)
			(effects
				(font
					(size 1.27 1.27)
				)
				(justify left bottom)
				(hide yes)
			)
		)
		(property "Value" "GND"
			(at 90.17 96.52 0)
			(effects
				(font
					(size 1.27 1.27)
					(thickness 0.15)
				)
			)
		)
		(property "Footprint" ""
			(at 99.06 100.33 0)
			(effects
				(font
					(size 1.27 1.27)
					(thickness 0.15)
				)
				(justify left bottom)
				(hide yes)
			)
		)
		(property "Datasheet" ""
			(at 99.06 105.41 0)
			(effects
				(font
					(size 1.27 1.27)
					(thickness 0.15)
				)
				(justify left bottom)
				(hide yes)
			)
		)
		(property "Description" ""
			(at 90.17 92.71 0)
			(effects
				(font
					(size 1.27 1.27)
				)
				(hide yes)
			)
		)
		(property "Author" "Antmicro"
			(at 99.06 100.33 0)
			(effects
				(font
					(size 1.27 1.27)
					(thickness 0.15)
				)
				(justify left bottom)
				(hide yes)
			)
		)
		(property "License" "Apache-2.0"
			(at 99.06 102.87 0)
			(effects
				(font
					(size 1.27 1.27)
					(thickness 0.15)
				)
				(justify left bottom)
				(hide yes)
			)
		)
		(pin "1"
		)
		(instances
			(project "jetson-agx-thor-baseboard"
				(path ""
					(reference "#PWR03")
					(unit 1)
				)
			)
		)
	)
	(symbol
		(lib_id "antmicroTestPoints:TP_0.75mm_SMD")
		(at 373.38 60.96 0)
		(unit 1)
		(exclude_from_sim no)
		(in_bom no)
		(on_board yes)
		(dnp no)
		(property "Reference" "TP105"
			(at 377.698 60.96 0)
			(effects
				(font
					(size 1.27 1.27)
				)
				(justify left)
			)
		)
		(property "Value" "TP_0.75mm_SMD"
			(at 383.54 64.77 0)
			(effects
				(font
					(size 1.27 1.27)
					(thickness 0.15)
				)
				(justify left bottom)
				(hide yes)
			)
		)
		(property "Footprint" "antmicro-footprints:TP_SMD_0.75mm"
			(at 383.54 67.31 0)
			(effects
				(font
					(size 1.27 1.27)
					(thickness 0.15)
				)
				(justify left bottom)
				(hide yes)
			)
		)
		(property "Datasheet" ""
			(at 391.16 73.66 0)
			(effects
				(font
					(size 1.27 1.27)
					(thickness 0.15)
				)
				(justify left bottom)
				(hide yes)
			)
		)
		(property "Description" "SMT test point"
			(at 373.38 60.96 0)
			(effects
				(font
					(size 1.27 1.27)
				)
				(hide yes)
			)
		)
		(property "MPN" ""
			(at 384.175 72.39 0)
			(effects
				(font
					(size 1.27 1.27)
					(thickness 0.15)
				)
				(justify left bottom)
				(hide yes)
			)
		)
		(property "Manufacturer" ""
			(at 384.175 67.31 0)
			(effects
				(font
					(size 1.27 1.27)
					(thickness 0.15)
				)
				(justify left bottom)
				(hide yes)
			)
		)
		(property "Author" "Antmicro"
			(at 383.54 69.85 0)
			(effects
				(font
					(size 1.27 1.27)
					(thickness 0.15)
				)
				(justify left bottom)
				(hide yes)
			)
		)
		(property "License" "Apache-2.0"
			(at 383.54 72.39 0)
			(effects
				(font
					(size 1.27 1.27)
					(thickness 0.15)
				)
				(justify left bottom)
				(hide yes)
			)
		)
		(pin "1"
		)
		(instances
			(project "jetson-agx-thor-baseboard"
				(path ""
					(reference "TP105")
					(unit 1)
				)
			)
		)
	)
	(symbol
		(lib_id "antmicroResistors0402:R_2k2_0402")
		(at 125.73 100.33 270)
		(unit 1)
		(exclude_from_sim no)
		(in_bom yes)
		(on_board yes)
		(dnp no)
		(fields_autoplaced yes)
		(property "Reference" "R375"
			(at 128.27 101.6 90)
			(effects
				(font
					(size 1.27 1.27)
					(thickness 0.15)
				)
				(justify left)
			)
		)
		(property "Value" "R_2k2_0402"
			(at 113.03 120.65 0)
			(effects
				(font
					(size 1.27 1.27)
					(thickness 0.15)
				)
				(justify left bottom)
				(hide yes)
			)
		)
		(property "Footprint" "antmicro-footprints:R_0402_1005Metric"
			(at 110.49 120.65 0)
			(effects
				(font
					(size 1.27 1.27)
					(thickness 0.15)
				)
				(justify left bottom)
				(hide yes)
			)
		)
		(property "Datasheet" "https://www.bourns.com/docs/product-datasheets/cr.pdf"
			(at 107.95 120.65 0)
			(effects
				(font
					(size 1.27 1.27)
					(thickness 0.15)
				)
				(justify left bottom)
				(hide yes)
			)
		)
		(property "Description" "SMD Chip Resistor, 2.2 kohm, ± 1%, 62.5 mW, 0402 [1005 Metric], Thick Film, General Purpose"
			(at 95.25 120.65 0)
			(effects
				(font
					(size 1.27 1.27)
				)
				(justify left bottom)
				(hide yes)
			)
		)
		(property "MPN" "CR0402-FX-2201GLF"
			(at 105.41 120.65 0)
			(effects
				(font
					(size 1.27 1.27)
					(thickness 0.15)
				)
				(justify left bottom)
				(hide yes)
			)
		)
		(property "Manufacturer" "Bourns"
			(at 102.87 120.65 0)
			(effects
				(font
					(size 1.27 1.27)
					(thickness 0.15)
				)
				(justify left bottom)
				(hide yes)
			)
		)
		(property "License" "Apache-2.0"
			(at 100.33 120.65 0)
			(effects
				(font
					(size 1.27 1.27)
					(thickness 0.15)
				)
				(justify left bottom)
				(hide yes)
			)
		)
		(property "Author" "Antmicro"
			(at 97.79 120.65 0)
			(effects
				(font
					(size 1.27 1.27)
					(thickness 0.15)
				)
				(justify left bottom)
				(hide yes)
			)
		)
		(property "Val" "2k2"
			(at 128.27 104.14 90)
			(effects
				(font
					(size 1.27 1.27)
					(thickness 0.15)
				)
				(justify left)
			)
		)
		(property "Tolerance" "1%"
			(at 115.57 120.65 0)
			(effects
				(font
					(size 1.27 1.27)
				)
				(justify left bottom)
				(hide yes)
			)
		)
		(pin "2"
		)
		(pin "1"
		)
		(instances
			(project "jetson-agx-thor-baseboard"
				(path ""
					(reference "R375")
					(unit 1)
				)
			)
		)
	)
	(symbol
		(lib_id "antmicropower:+1V8")
		(at 90.17 34.29 0)
		(unit 1)
		(exclude_from_sim no)
		(in_bom yes)
		(on_board yes)
		(dnp no)
		(property "Reference" "#PWR023"
			(at 90.17 38.1 0)
			(effects
				(font
					(size 1.27 1.27)
				)
				(justify left bottom)
				(hide yes)
			)
		)
		(property "Value" "+1V8"
			(at 86.995 30.48 0)
			(effects
				(font
					(size 1.27 1.27)
					(thickness 0.15)
				)
				(justify left)
			)
		)
		(property "Footprint" ""
			(at 105.41 41.91 0)
			(effects
				(font
					(size 1.27 1.27)
					(thickness 0.15)
				)
				(justify left bottom)
				(hide yes)
			)
		)
		(property "Datasheet" ""
			(at 105.41 44.45 0)
			(effects
				(font
					(size 1.27 1.27)
					(thickness 0.15)
				)
				(justify left bottom)
				(hide yes)
			)
		)
		(property "Description" ""
			(at 90.17 34.29 0)
			(effects
				(font
					(size 1.27 1.27)
				)
				(hide yes)
			)
		)
		(property "Author" "Antmicro"
			(at 105.41 39.37 0)
			(effects
				(font
					(size 1.27 1.27)
					(thickness 0.15)
				)
				(justify left bottom)
				(hide yes)
			)
		)
		(property "License" "Apache-2.0"
			(at 105.41 41.91 0)
			(effects
				(font
					(size 1.27 1.27)
					(thickness 0.15)
				)
				(justify left bottom)
				(hide yes)
			)
		)
		(pin "1"
		)
		(instances
			(project "jetson-agx-thor-baseboard"
				(path ""
					(reference "#PWR023")
					(unit 1)
				)
			)
		)
	)
	(symbol
		(lib_id "antmicropower:+1V8")
		(at 83.82 53.34 0)
		(unit 1)
		(exclude_from_sim no)
		(in_bom yes)
		(on_board yes)
		(dnp no)
		(property "Reference" "#PWR014"
			(at 83.82 57.15 0)
			(effects
				(font
					(size 1.27 1.27)
				)
				(justify left bottom)
				(hide yes)
			)
		)
		(property "Value" "+1V8"
			(at 80.645 49.53 0)
			(effects
				(font
					(size 1.27 1.27)
					(thickness 0.15)
				)
				(justify left)
			)
		)
		(property "Footprint" ""
			(at 99.06 60.96 0)
			(effects
				(font
					(size 1.27 1.27)
					(thickness 0.15)
				)
				(justify left bottom)
				(hide yes)
			)
		)
		(property "Datasheet" ""
			(at 99.06 63.5 0)
			(effects
				(font
					(size 1.27 1.27)
					(thickness 0.15)
				)
				(justify left bottom)
				(hide yes)
			)
		)
		(property "Description" ""
			(at 83.82 53.34 0)
			(effects
				(font
					(size 1.27 1.27)
				)
				(hide yes)
			)
		)
		(property "Author" "Antmicro"
			(at 99.06 58.42 0)
			(effects
				(font
					(size 1.27 1.27)
					(thickness 0.15)
				)
				(justify left bottom)
				(hide yes)
			)
		)
		(property "License" "Apache-2.0"
			(at 99.06 60.96 0)
			(effects
				(font
					(size 1.27 1.27)
					(thickness 0.15)
				)
				(justify left bottom)
				(hide yes)
			)
		)
		(pin "1"
		)
		(instances
			(project "jetson-agx-thor-baseboard"
				(path ""
					(reference "#PWR014")
					(unit 1)
				)
			)
		)
	)
	(symbol
		(lib_id "antmicroLogicTranslatorsLevelShifters:NTS0104_DHVQFN")
		(at 85.09 54.61 0)
		(unit 1)
		(exclude_from_sim no)
		(in_bom yes)
		(on_board yes)
		(dnp no)
		(property "Reference" "U1"
			(at 95.504 48.26 0)
			(effects
				(font
					(size 1.27 1.27)
					(thickness 0.15)
				)
			)
		)
		(property "Value" "NTS0104_DHVQFN"
			(at 120.65 62.23 0)
			(effects
				(font
					(size 1.27 1.27)
					(thickness 0.15)
				)
				(justify left bottom)
				(hide yes)
			)
		)
		(property "Footprint" "antmicro-footprints:DHVQFN-14-1EP_2.5x3mm"
			(at 120.65 64.77 0)
			(effects
				(font
					(size 1.27 1.27)
					(thickness 0.15)
				)
				(justify left bottom)
				(hide yes)
			)
		)
		(property "Datasheet" "https://www.nxp.com/docs/en/data-sheet/NTS0104.pdf"
			(at 120.65 67.31 0)
			(effects
				(font
					(size 1.27 1.27)
					(thickness 0.15)
				)
				(justify left bottom)
				(hide yes)
			)
		)
		(property "Description" "Voltage Level Translator Bidirectional 1 Circuit 4 Channel 50Mbps 14-DHVQFN (2.5x3)"
			(at 120.65 77.47 0)
			(effects
				(font
					(size 1.27 1.27)
				)
				(justify left bottom)
				(hide yes)
			)
		)
		(property "MPN" "NTS0104BQ"
			(at 95.504 50.8 0)
			(effects
				(font
					(size 1.27 1.27)
					(thickness 0.15)
				)
			)
		)
		(property "Manufacturer" "NXP"
			(at 120.65 69.85 0)
			(effects
				(font
					(size 1.27 1.27)
					(thickness 0.15)
				)
				(justify left bottom)
				(hide yes)
			)
		)
		(property "Author" "Antmicro"
			(at 120.65 72.39 0)
			(effects
				(font
					(size 1.27 1.27)
					(thickness 0.15)
				)
				(justify left bottom)
				(hide yes)
			)
		)
		(property "License" "Apache-2.0"
			(at 120.65 74.93 0)
			(effects
				(font
					(size 1.27 1.27)
					(thickness 0.15)
				)
				(justify left bottom)
				(hide yes)
			)
		)
		(pin "9"
		)
		(pin "11"
		)
		(pin "15"
		)
		(pin "4"
		)
		(pin "12"
		)
		(pin "5"
		)
		(pin "13"
		)
		(pin "10"
		)
		(pin "3"
		)
		(pin "2"
		)
		(pin "8"
		)
		(pin "1"
		)
		(pin "6"
		)
		(pin "7"
		)
		(pin "14"
		)
		(instances
			(project "jetson-agx-thor-baseboard"
				(path ""
					(reference "U1")
					(unit 1)
				)
			)
		)
	)
	(symbol
		(lib_id "antmicroB2BConnectors:Hermaphroditic_Molex_203456-0003_CUSTOM_Jetson_AGX_Thor_H8mm")
		(at 320.04 208.28 0)
		(unit 8)
		(exclude_from_sim no)
		(in_bom yes)
		(on_board yes)
		(dnp no)
		(fields_autoplaced yes)
		(property "Reference" "J1"
			(at 342.9 200.66 0)
			(effects
				(font
					(size 1.27 1.27)
				)
			)
		)
		(property "Value" "Hermaphroditic_Molex_203456-0003_CUSTOM_Jetson_AGX_Thor_H8mm"
			(at 396.494 214.376 0)
			(effects
				(font
					(size 1.27 1.27)
				)
				(justify left bottom)
				(hide yes)
			)
		)
		(property "Footprint" "antmicro-footprints:Conn_Hermaphroditic_Molex_203456-0003_mirrored"
			(at 396.494 216.662 0)
			(effects
				(font
					(size 1.27 1.27)
				)
				(justify left bottom)
				(hide yes)
			)
		)
		(property "Datasheet" "https://www.molex.com/content/dam/molex/molex-dot-com/products/automated/en-us/salesdrawingpdf/203/203456/2034560003_sd.pdf?inline"
			(at 396.494 218.948 0)
			(effects
				(font
					(size 1.27 1.27)
				)
				(justify left bottom)
				(hide yes)
			)
		)
		(property "Description" "Mirror Mezz Hermaphroditic Connector, 5.50mm Connector Height, BGA-Attach Mounting, 7 Pair, 11 Row, 699 Circuits, 0.76µm Gold Plating, without Pegs"
			(at 396.494 227.584 0)
			(effects
				(font
					(size 1.27 1.27)
				)
				(justify left bottom)
				(hide yes)
			)
		)
		(property "MPN" "203456-0003"
			(at 342.9 203.2 0)
			(effects
				(font
					(size 1.27 1.27)
				)
			)
		)
		(property "Manufacturer" "Molex"
			(at 396.494 221.234 0)
			(effects
				(font
					(size 1.27 1.27)
				)
				(justify left bottom)
				(hide yes)
			)
		)
		(property "Author" "Antmicro"
			(at 396.494 223.266 0)
			(effects
				(font
					(size 1.27 1.27)
				)
				(justify left bottom)
				(hide yes)
			)
		)
		(property "License" "Apache-2.0"
			(at 396.494 225.298 0)
			(effects
				(font
					(size 1.27 1.27)
				)
				(justify left bottom)
				(hide yes)
			)
		)
		(pin "L27"
		)
		(pin "A33"
		)
		(pin "J65"
		)
		(pin "A29"
		)
		(pin "D63"
		)
		(pin "G2"
		)
		(pin "J64"
		)
		(pin "F65"
		)
		(pin "D64"
		)
		(pin "L22"
		)
		(pin "D2"
		)
		(pin "G33"
		)
		(pin "F3"
		)
		(pin "H64"
		)
		(pin "H3"
		)
		(pin "G65"
		)
		(pin "F1"
		)
		(pin "J63"
		)
		(pin "D65"
		)
		(pin "B44"
		)
		(pin "F11"
		)
		(pin "B39"
		)
		(pin "E36"
		)
		(pin "B11"
		)
		(pin "D57"
		)
		(pin "E21"
		)
		(pin "E28"
		)
		(pin "E24"
		)
		(pin "E12"
		)
		(pin "C9"
		)
		(pin "D39"
		)
		(pin "E65"
		)
		(pin "H1"
		)
		(pin "D3"
		)
		(pin "H2"
		)
		(pin "F51"
		)
		(pin "A55"
		)
		(pin "J2"
		)
		(pin "F63"
		)
		(pin "L55"
		)
		(pin "B19"
		)
		(pin "B38"
		)
		(pin "E32"
		)
		(pin "G36"
		)
		(pin "E37"
		)
		(pin "E64"
		)
		(pin "L23"
		)
		(pin "A46"
		)
		(pin "H65"
		)
		(pin "C55"
		)
		(pin "B53"
		)
		(pin "C13"
		)
		(pin "C34"
		)
		(pin "C35"
		)
		(pin "F19"
		)
		(pin "L47"
		)
		(pin "C63"
		)
		(pin "E46"
		)
		(pin "C29"
		)
		(pin "H31"
		)
		(pin "D37"
		)
		(pin "H41"
		)
		(pin "J32"
		)
		(pin "G5"
		)
		(pin "B55"
		)
		(pin "L60"
		)
		(pin "B10"
		)
		(pin "K52"
		)
		(pin "K51"
		)
		(pin "E6"
		)
		(pin "F44"
		)
		(pin "C23"
		)
		(pin "C22"
		)
		(pin "L42"
		)
		(pin "E29"
		)
		(pin "A16"
		)
		(pin "E16"
		)
		(pin "D7"
		)
		(pin "K15"
		)
		(pin "L31"
		)
		(pin "G62"
		)
		(pin "F6"
		)
		(pin "H16"
		)
		(pin "G18"
		)
		(pin "F4"
		)
		(pin "C12"
		)
		(pin "K31"
		)
		(pin "B7"
		)
		(pin "B57"
		)
		(pin "E2"
		)
		(pin "F14"
		)
		(pin "A9"
		)
		(pin "E52"
		)
		(pin "H56"
		)
		(pin "A37"
		)
		(pin "D34"
		)
		(pin "E62"
		)
		(pin "H34"
		)
		(pin "D41"
		)
		(pin "F15"
		)
		(pin "A32"
		)
		(pin "B35"
		)
		(pin "D4"
		)
		(pin "D26"
		)
		(pin "G13"
		)
		(pin "B41"
		)
		(pin "B30"
		)
		(pin "F23"
		)
		(pin "A12"
		)
		(pin "L20"
		)
		(pin "J29"
		)
		(pin "G63"
		)
		(pin "A22"
		)
		(pin "A23"
		)
		(pin "H35"
		)
		(pin "K34"
		)
		(pin "L13"
		)
		(pin "K35"
		)
		(pin "J3"
		)
		(pin "C49"
		)
		(pin "L53"
		)
		(pin "J36"
		)
		(pin "D15"
		)
		(pin "E33"
		)
		(pin "G32"
		)
		(pin "A63"
		)
		(pin "L12"
		)
		(pin "B50"
		)
		(pin "C33"
		)
		(pin "D38"
		)
		(pin "G29"
		)
		(pin "L51"
		)
		(pin "H54"
		)
		(pin "K53"
		)
		(pin "K54"
		)
		(pin "L61"
		)
		(pin "L58"
		)
		(pin "G3"
		)
		(pin "G43"
		)
		(pin "C28"
		)
		(pin "L8"
		)
		(pin "J61"
		)
		(pin "D40"
		)
		(pin "B40"
		)
		(pin "K36"
		)
		(pin "D44"
		)
		(pin "F27"
		)
		(pin "D53"
		)
		(pin "K19"
		)
		(pin "J57"
		)
		(pin "A56"
		)
		(pin "D55"
		)
		(pin "K8"
		)
		(pin "L16"
		)
		(pin "J12"
		)
		(pin "D23"
		)
		(pin "F34"
		)
		(pin "H4"
		)
		(pin "F54"
		)
		(pin "G55"
		)
		(pin "K7"
		)
		(pin "H9"
		)
		(pin "L14"
		)
		(pin "G39"
		)
		(pin "G38"
		)
		(pin "H36"
		)
		(pin "H37"
		)
		(pin "K40"
		)
		(pin "K45"
		)
		(pin "F10"
		)
		(pin "F9"
		)
		(pin "C39"
		)
		(pin "A58"
		)
		(pin "F49"
		)
		(pin "G48"
		)
		(pin "G47"
		)
		(pin "K42"
		)
		(pin "G23"
		)
		(pin "G22"
		)
		(pin "H10"
		)
		(pin "L18"
		)
		(pin "L26"
		)
		(pin "L34"
		)
		(pin "G37"
		)
		(pin "H60"
		)
		(pin "C61"
		)
		(pin "A62"
		)
		(pin "G7"
		)
		(pin "L15"
		)
		(pin "J56"
		)
		(pin "F26"
		)
		(pin "H15"
		)
		(pin "H40"
		)
		(pin "J20"
		)
		(pin "F7"
		)
		(pin "D8"
		)
		(pin "C7"
		)
		(pin "H8"
		)
		(pin "L9"
		)
		(pin "L48"
		)
		(pin "J54"
		)
		(pin "J28"
		)
		(pin "B16"
		)
		(pin "B17"
		)
		(pin "K39"
		)
		(pin "B51"
		)
		(pin "B52"
		)
		(pin "A13"
		)
		(pin "E3"
		)
		(pin "B14"
		)
		(pin "B42"
		)
		(pin "A41"
		)
		(pin "A42"
		)
		(pin "D22"
		)
		(pin "G15"
		)
		(pin "G14"
		)
		(pin "A52"
		)
		(pin "C21"
		)
		(pin "G52"
		)
		(pin "K62"
		)
		(pin "E58"
		)
		(pin "B60"
		)
		(pin "A60"
		)
		(pin "J21"
		)
		(pin "K22"
		)
		(pin "J4"
		)
		(pin "B59"
		)
		(pin "A59"
		)
		(pin "B62"
		)
		(pin "H32"
		)
		(pin "H33"
		)
		(pin "K50"
		)
		(pin "D19"
		)
		(pin "H28"
		)
		(pin "H29"
		)
		(pin "B34"
		)
		(pin "H22"
		)
		(pin "H49"
		)
		(pin "H48"
		)
		(pin "L36"
		)
		(pin "L37"
		)
		(pin "J37"
		)
		(pin "F30"
		)
		(pin "H24"
		)
		(pin "H25"
		)
		(pin "A3"
		)
		(pin "G4"
		)
		(pin "E4"
		)
		(pin "F5"
		)
		(pin "G51"
		)
		(pin "G50"
		)
		(pin "B47"
		)
		(pin "C16"
		)
		(pin "G40"
		)
		(pin "C43"
		)
		(pin "J34"
		)
		(pin "A34"
		)
		(pin "A35"
		)
		(pin "L30"
		)
		(pin "B27"
		)
		(pin "G64"
		)
		(pin "K23"
		)
		(pin "G17"
		)
		(pin "F16"
		)
		(pin "F17"
		)
		(pin "H19"
		)
		(pin "G12"
		)
		(pin "B12"
		)
		(pin "B13"
		)
		(pin "J24"
		)
		(pin "E9"
		)
		(pin "L17"
		)
		(pin "L32"
		)
		(pin "L33"
		)
		(pin "F32"
		)
		(pin "F33"
		)
		(pin "K38"
		)
		(pin "E63"
		)
		(pin "F64"
		)
		(pin "E1"
		)
		(pin "G24"
		)
		(pin "D1"
		)
		(pin "F18"
		)
		(pin "H51"
		)
		(pin "J52"
		)
		(pin "F39"
		)
		(pin "J43"
		)
		(pin "E15"
		)
		(pin "E14"
		)
		(pin "L24"
		)
		(pin "H5"
		)
		(pin "K6"
		)
		(pin "J5"
		)
		(pin "J6"
		)
		(pin "L59"
		)
		(pin "K3"
		)
		(pin "D28"
		)
		(pin "D29"
		)
		(pin "C25"
		)
		(pin "A15"
		)
		(pin "A14"
		)
		(pin "K30"
		)
		(pin "D35"
		)
		(pin "J46"
		)
		(pin "F57"
		)
		(pin "F42"
		)
		(pin "E42"
		)
		(pin "E41"
		)
		(pin "A24"
		)
		(pin "C46"
		)
		(pin "J60"
		)
		(pin "F61"
		)
		(pin "H27"
		)
		(pin "B18"
		)
		(pin "A43"
		)
		(pin "D27"
		)
		(pin "H14"
		)
		(pin "A17"
		)
		(pin "F24"
		)
		(pin "F25"
		)
		(pin "A51"
		)
		(pin "A50"
		)
		(pin "C51"
		)
		(pin "C50"
		)
		(pin "C1"
		)
		(pin "J22"
		)
		(pin "J23"
		)
		(pin "C2"
		)
		(pin "B3"
		)
		(pin "G35"
		)
		(pin "G34"
		)
		(pin "B63"
		)
		(pin "A28"
		)
		(pin "B31"
		)
		(pin "C64"
		)
		(pin "C60"
		)
		(pin "K59"
		)
		(pin "J59"
		)
		(pin "C42"
		)
		(pin "C41"
		)
		(pin "F46"
		)
		(pin "K26"
		)
		(pin "D49"
		)
		(pin "D48"
		)
		(pin "G58"
		)
		(pin "A57"
		)
		(pin "C58"
		)
		(pin "C56"
		)
		(pin "D46"
		)
		(pin "D45"
		)
		(pin "J44"
		)
		(pin "K46"
		)
		(pin "K47"
		)
		(pin "J47"
		)
		(pin "J48"
		)
		(pin "D14"
		)
		(pin "F20"
		)
		(pin "F21"
		)
		(pin "F43"
		)
		(pin "J62"
		)
		(pin "B21"
		)
		(pin "B20"
		)
		(pin "E47"
		)
		(pin "E48"
		)
		(pin "C44"
		)
		(pin "H17"
		)
		(pin "G19"
		)
		(pin "C59"
		)
		(pin "F60"
		)
		(pin "C57"
		)
		(pin "E56"
		)
		(pin "J53"
		)
		(pin "K5"
		)
		(pin "G31"
		)
		(pin "G30"
		)
		(pin "D11"
		)
		(pin "H44"
		)
		(pin "L46"
		)
		(pin "L7"
		)
		(pin "L25"
		)
		(pin "B23"
		)
		(pin "F58"
		)
		(pin "D59"
		)
		(pin "B61"
		)
		(pin "H61"
		)
		(pin "J41"
		)
		(pin "J42"
		)
		(pin "B43"
		)
		(pin "B29"
		)
		(pin "B28"
		)
		(pin "D51"
		)
		(pin "D52"
		)
		(pin "F62"
		)
		(pin "E51"
		)
		(pin "E50"
		)
		(pin "K56"
		)
		(pin "K55"
		)
		(pin "F45"
		)
		(pin "E45"
		)
		(pin "E44"
		)
		(pin "A8"
		)
		(pin "K49"
		)
		(pin "K21"
		)
		(pin "K20"
		)
		(pin "E13"
		)
		(pin "C52"
		)
		(pin "H26"
		)
		(pin "J49"
		)
		(pin "D47"
		)
		(pin "B25"
		)
		(pin "B24"
		)
		(pin "L28"
		)
		(pin "K4"
		)
		(pin "D20"
		)
		(pin "D21"
		)
		(pin "E25"
		)
		(pin "G20"
		)
		(pin "H42"
		)
		(pin "G41"
		)
		(pin "G42"
		)
		(pin "L10"
		)
		(pin "L11"
		)
		(pin "H23"
		)
		(pin "B37"
		)
		(pin "E11"
		)
		(pin "H63"
		)
		(pin "E34"
		)
		(pin "F37"
		)
		(pin "F36"
		)
		(pin "E35"
		)
		(pin "E7"
		)
		(pin "F8"
		)
		(pin "A4"
		)
		(pin "J26"
		)
		(pin "J27"
		)
		(pin "L35"
		)
		(pin "J11"
		)
		(pin "E27"
		)
		(pin "A21"
		)
		(pin "K18"
		)
		(pin "B33"
		)
		(pin "B32"
		)
		(pin "E60"
		)
		(pin "A53"
		)
		(pin "E23"
		)
		(pin "E22"
		)
		(pin "D50"
		)
		(pin "G57"
		)
		(pin "C53"
		)
		(pin "K10"
		)
		(pin "F22"
		)
		(pin "H20"
		)
		(pin "H21"
		)
		(pin "G11"
		)
		(pin "G10"
		)
		(pin "B26"
		)
		(pin "J16"
		)
		(pin "J40"
		)
		(pin "K14"
		)
		(pin "G8"
		)
		(pin "C8"
		)
		(pin "B58"
		)
		(pin "H52"
		)
		(pin "C38"
		)
		(pin "A18"
		)
		(pin "G49"
		)
		(pin "J55"
		)
		(pin "A47"
		)
		(pin "A40"
		)
		(pin "L52"
		)
		(pin "A6"
		)
		(pin "J13"
		)
		(pin "B22"
		)
		(pin "G16"
		)
		(pin "F38"
		)
		(pin "F2"
		)
		(pin "F50"
		)
		(pin "H7"
		)
		(pin "F35"
		)
		(pin "G1"
		)
		(pin "K13"
		)
		(pin "K12"
		)
		(pin "G46"
		)
		(pin "J58"
		)
		(pin "H58"
		)
		(pin "K57"
		)
		(pin "E54"
		)
		(pin "G21"
		)
		(pin "D16"
		)
		(pin "D17"
		)
		(pin "A19"
		)
		(pin "A38"
		)
		(pin "E5"
		)
		(pin "B54"
		)
		(pin "A54"
		)
		(pin "E39"
		)
		(pin "E38"
		)
		(pin "H43"
		)
		(pin "K17"
		)
		(pin "K16"
		)
		(pin "J45"
		)
		(pin "K44"
		)
		(pin "K43"
		)
		(pin "D58"
		)
		(pin "G61"
		)
		(pin "H59"
		)
		(pin "G60"
		)
		(pin "F41"
		)
		(pin "H11"
		)
		(pin "C6"
		)
		(pin "G59"
		)
		(pin "E53"
		)
		(pin "D61"
		)
		(pin "L56"
		)
		(pin "A61"
		)
		(pin "C31"
		)
		(pin "C30"
		)
		(pin "K41"
		)
		(pin "K63"
		)
		(pin "H47"
		)
		(pin "D18"
		)
		(pin "L54"
		)
		(pin "L62"
		)
		(pin "K11"
		)
		(pin "G27"
		)
		(pin "G26"
		)
		(pin "D10"
		)
		(pin "J9"
		)
		(pin "C20"
		)
		(pin "L19"
		)
		(pin "B36"
		)
		(pin "L39"
		)
		(pin "C62"
		)
		(pin "C17"
		)
		(pin "C32"
		)
		(pin "A48"
		)
		(pin "H55"
		)
		(pin "B8"
		)
		(pin "L50"
		)
		(pin "L49"
		)
		(pin "F31"
		)
		(pin "H62"
		)
		(pin "K60"
		)
		(pin "L4"
		)
		(pin "L6"
		)
		(pin "C54"
		)
		(pin "D54"
		)
		(pin "J51"
		)
		(pin "J33"
		)
		(pin "F56"
		)
		(pin "A39"
		)
		(pin "E59"
		)
		(pin "F59"
		)
		(pin "L57"
		)
		(pin "L44"
		)
		(pin "F12"
		)
		(pin "F13"
		)
		(pin "D30"
		)
		(pin "C45"
		)
		(pin "D42"
		)
		(pin "D43"
		)
		(pin "A25"
		)
		(pin "H38"
		)
		(pin "K37"
		)
		(pin "L41"
		)
		(pin "C37"
		)
		(pin "G28"
		)
		(pin "E43"
		)
		(pin "J1"
		)
		(pin "J17"
		)
		(pin "D33"
		)
		(pin "D32"
		)
		(pin "J35"
		)
		(pin "H18"
		)
		(pin "E20"
		)
		(pin "L5"
		)
		(pin "H6"
		)
		(pin "K58"
		)
		(pin "H57"
		)
		(pin "B15"
		)
		(pin "J38"
		)
		(pin "J39"
		)
		(pin "D36"
		)
		(pin "H50"
		)
		(pin "B48"
		)
		(pin "B49"
		)
		(pin "B9"
		)
		(pin "F47"
		)
		(pin "E57"
		)
		(pin "D31"
		)
		(pin "E30"
		)
		(pin "D9"
		)
		(pin "B5"
		)
		(pin "E49"
		)
		(pin "C3"
		)
		(pin "A30"
		)
		(pin "A31"
		)
		(pin "E19"
		)
		(pin "E18"
		)
		(pin "C19"
		)
		(pin "C36"
		)
		(pin "K48"
		)
		(pin "J10"
		)
		(pin "K9"
		)
		(pin "E31"
		)
		(pin "F55"
		)
		(pin "D56"
		)
		(pin "G56"
		)
		(pin "G44"
		)
		(pin "G45"
		)
		(pin "F48"
		)
		(pin "J7"
		)
		(pin "J19"
		)
		(pin "C47"
		)
		(pin "C48"
		)
		(pin "F40"
		)
		(pin "D24"
		)
		(pin "D25"
		)
		(pin "K61"
		)
		(pin "F53"
		)
		(pin "D60"
		)
		(pin "E61"
		)
		(pin "D62"
		)
		(pin "L40"
		)
		(pin "L43"
		)
		(pin "L63"
		)
		(pin "K27"
		)
		(pin "B46"
		)
		(pin "A44"
		)
		(pin "A45"
		)
		(pin "B4"
		)
		(pin "G25"
		)
		(pin "L29"
		)
		(pin "L3"
		)
		(pin "K25"
		)
		(pin "K24"
		)
		(pin "A26"
		)
		(pin "A27"
		)
		(pin "H39"
		)
		(pin "E17"
		)
		(pin "G9"
		)
		(pin "C4"
		)
		(pin "D5"
		)
		(pin "G6"
		)
		(pin "J18"
		)
		(pin "E26"
		)
		(pin "F52"
		)
		(pin "H12"
		)
		(pin "H13"
		)
		(pin "A10"
		)
		(pin "A11"
		)
		(pin "K29"
		)
		(pin "K28"
		)
		(pin "A7"
		)
		(pin "E10"
		)
		(pin "C5"
		)
		(pin "D6"
		)
		(pin "B6"
		)
		(pin "A5"
		)
		(pin "E8"
		)
		(pin "A49"
		)
		(pin "A36"
		)
		(pin "H46"
		)
		(pin "H45"
		)
		(pin "B45"
		)
		(pin "J30"
		)
		(pin "J31"
		)
		(pin "C15"
		)
		(pin "C14"
		)
		(pin "J14"
		)
		(pin "J15"
		)
		(pin "C27"
		)
		(pin "C26"
		)
		(pin "K32"
		)
		(pin "K33"
		)
		(pin "J8"
		)
		(pin "J25"
		)
		(pin "L38"
		)
		(pin "C40"
		)
		(pin "D12"
		)
		(pin "D13"
		)
		(pin "A20"
		)
		(pin "H30"
		)
		(pin "E40"
		)
		(pin "L21"
		)
		(pin "H53"
		)
		(pin "E55"
		)
		(pin "B56"
		)
		(pin "F28"
		)
		(pin "F29"
		)
		(pin "C11"
		)
		(pin "C10"
		)
		(pin "L45"
		)
		(pin "J50"
		)
		(pin "C65"
		)
		(pin "G53"
		)
		(pin "G54"
		)
		(pin "C18"
		)
		(pin "C24"
		)
		(instances
			(project ""
				(path ""
					(reference "J1")
					(unit 8)
				)
			)
		)
	)
	(symbol
		(lib_id "antmicropower:+3V3")
		(at 106.68 104.14 0)
		(unit 1)
		(exclude_from_sim no)
		(in_bom yes)
		(on_board yes)
		(dnp no)
		(property "Reference" "#PWR017"
			(at 106.68 107.95 0)
			(effects
				(font
					(size 1.27 1.27)
				)
				(justify left bottom)
				(hide yes)
			)
		)
		(property "Value" "+3V3"
			(at 103.505 100.33 0)
			(effects
				(font
					(size 1.27 1.27)
					(thickness 0.15)
				)
				(justify left)
			)
		)
		(property "Footprint" ""
			(at 121.92 111.76 0)
			(effects
				(font
					(size 1.27 1.27)
					(thickness 0.15)
				)
				(justify left bottom)
				(hide yes)
			)
		)
		(property "Datasheet" ""
			(at 121.92 114.3 0)
			(effects
				(font
					(size 1.27 1.27)
					(thickness 0.15)
				)
				(justify left bottom)
				(hide yes)
			)
		)
		(property "Description" ""
			(at 106.68 104.14 0)
			(effects
				(font
					(size 1.27 1.27)
				)
				(hide yes)
			)
		)
		(property "Author" "Antmicro"
			(at 121.92 106.68 0)
			(effects
				(font
					(size 1.27 1.27)
					(thickness 0.15)
				)
				(justify left bottom)
				(hide yes)
			)
		)
		(property "License" "Apache-2.0"
			(at 121.92 109.22 0)
			(effects
				(font
					(size 1.27 1.27)
					(thickness 0.15)
				)
				(justify left bottom)
				(hide yes)
			)
		)
		(pin "1"
		)
		(instances
			(project "jetson-agx-thor-baseboard"
				(path ""
					(reference "#PWR017")
					(unit 1)
				)
			)
		)
	)
	(symbol
		(lib_id "antmicroCapacitors0402:C_100n_0402")
		(at 100.33 40.64 270)
		(mirror x)
		(unit 1)
		(exclude_from_sim no)
		(in_bom yes)
		(on_board yes)
		(dnp no)
		(property "Reference" "C10"
			(at 102.235 36.83 90)
			(effects
				(font
					(size 1.27 1.27)
				)
				(justify left)
			)
		)
		(property "Value" "C_100n_0402"
			(at 90.17 20.32 0)
			(effects
				(font
					(size 1.27 1.27)
					(thickness 0.15)
				)
				(justify left bottom)
				(hide yes)
			)
		)
		(property "Footprint" "antmicro-footprints:C_0402_1005Metric"
			(at 87.63 20.32 0)
			(effects
				(font
					(size 1.27 1.27)
					(thickness 0.15)
				)
				(justify left bottom)
				(hide yes)
			)
		)
		(property "Datasheet" "https://www.murata.com/products/productdetail?partno=GRM155R61H104KE14%23"
			(at 85.09 20.32 0)
			(effects
				(font
					(size 1.27 1.27)
					(thickness 0.15)
				)
				(justify left bottom)
				(hide yes)
			)
		)
		(property "Description" "SMD Multilayer Ceramic Capacitor, 0.1 µF, 50 V, 0402 [1005 Metric], ± 10%, X5R, GRM Series"
			(at 100.33 40.64 0)
			(effects
				(font
					(size 1.27 1.27)
				)
				(hide yes)
			)
		)
		(property "Manufacturer" "Murata"
			(at 80.01 20.32 0)
			(effects
				(font
					(size 1.27 1.27)
					(thickness 0.15)
				)
				(justify left bottom)
				(hide yes)
			)
		)
		(property "MPN" "GRM155R61H104KE14D"
			(at 82.55 20.32 0)
			(effects
				(font
					(size 1.27 1.27)
					(thickness 0.15)
				)
				(justify left bottom)
				(hide yes)
			)
		)
		(property "Val" "100n"
			(at 102.235 39.37 90)
			(effects
				(font
					(size 1.27 1.27)
					(thickness 0.15)
				)
				(justify left)
			)
		)
		(property "License" "Apache-2.0"
			(at 77.47 20.32 0)
			(effects
				(font
					(size 1.27 1.27)
					(thickness 0.15)
				)
				(justify left bottom)
				(hide yes)
			)
		)
		(property "Author" "Antmicro"
			(at 74.93 20.32 0)
			(effects
				(font
					(size 1.27 1.27)
					(thickness 0.15)
				)
				(justify left bottom)
				(hide yes)
			)
		)
		(property "Voltage" "50V"
			(at 72.39 20.32 0)
			(effects
				(font
					(size 1.27 1.27)
				)
				(justify left bottom)
				(hide yes)
			)
		)
		(property "Dielectric" "X5R"
			(at 69.85 20.32 0)
			(effects
				(font
					(size 1.27 1.27)
				)
				(justify left bottom)
				(hide yes)
			)
		)
		(pin "1"
		)
		(pin "2"
		)
		(instances
			(project "jetson-agx-thor-baseboard"
				(path ""
					(reference "C10")
					(unit 1)
				)
			)
		)
	)
	(symbol
		(lib_id "antmicropower:+1V8")
		(at 77.47 201.93 0)
		(unit 1)
		(exclude_from_sim no)
		(in_bom yes)
		(on_board yes)
		(dnp no)
		(property "Reference" "#PWR018"
			(at 77.47 205.74 0)
			(effects
				(font
					(size 1.27 1.27)
				)
				(justify left bottom)
				(hide yes)
			)
		)
		(property "Value" "+1V8"
			(at 74.295 198.12 0)
			(effects
				(font
					(size 1.27 1.27)
					(thickness 0.15)
				)
				(justify left)
			)
		)
		(property "Footprint" ""
			(at 92.71 209.55 0)
			(effects
				(font
					(size 1.27 1.27)
					(thickness 0.15)
				)
				(justify left bottom)
				(hide yes)
			)
		)
		(property "Datasheet" ""
			(at 92.71 212.09 0)
			(effects
				(font
					(size 1.27 1.27)
					(thickness 0.15)
				)
				(justify left bottom)
				(hide yes)
			)
		)
		(property "Description" ""
			(at 77.47 201.93 0)
			(effects
				(font
					(size 1.27 1.27)
				)
				(hide yes)
			)
		)
		(property "Author" "Antmicro"
			(at 92.71 207.01 0)
			(effects
				(font
					(size 1.27 1.27)
					(thickness 0.15)
				)
				(justify left bottom)
				(hide yes)
			)
		)
		(property "License" "Apache-2.0"
			(at 92.71 209.55 0)
			(effects
				(font
					(size 1.27 1.27)
					(thickness 0.15)
				)
				(justify left bottom)
				(hide yes)
			)
		)
		(pin "1"
		)
		(instances
			(project "jetson-agx-thor-baseboard"
				(path ""
					(reference "#PWR018")
					(unit 1)
				)
			)
		)
	)
	(symbol
		(lib_id "antmicropower:+3V3")
		(at 106.68 53.34 0)
		(unit 1)
		(exclude_from_sim no)
		(in_bom yes)
		(on_board yes)
		(dnp no)
		(property "Reference" "#PWR015"
			(at 106.68 57.15 0)
			(effects
				(font
					(size 1.27 1.27)
				)
				(justify left bottom)
				(hide yes)
			)
		)
		(property "Value" "+3V3"
			(at 103.505 49.53 0)
			(effects
				(font
					(size 1.27 1.27)
					(thickness 0.15)
				)
				(justify left)
			)
		)
		(property "Footprint" ""
			(at 121.92 60.96 0)
			(effects
				(font
					(size 1.27 1.27)
					(thickness 0.15)
				)
				(justify left bottom)
				(hide yes)
			)
		)
		(property "Datasheet" ""
			(at 121.92 63.5 0)
			(effects
				(font
					(size 1.27 1.27)
					(thickness 0.15)
				)
				(justify left bottom)
				(hide yes)
			)
		)
		(property "Description" ""
			(at 106.68 53.34 0)
			(effects
				(font
					(size 1.27 1.27)
				)
				(hide yes)
			)
		)
		(property "Author" "Antmicro"
			(at 121.92 55.88 0)
			(effects
				(font
					(size 1.27 1.27)
					(thickness 0.15)
				)
				(justify left bottom)
				(hide yes)
			)
		)
		(property "License" "Apache-2.0"
			(at 121.92 58.42 0)
			(effects
				(font
					(size 1.27 1.27)
					(thickness 0.15)
				)
				(justify left bottom)
				(hide yes)
			)
		)
		(pin "1"
		)
		(instances
			(project "jetson-agx-thor-baseboard"
				(path ""
					(reference "#PWR015")
					(unit 1)
				)
			)
		)
	)
	(symbol
		(lib_id "antmicroResistors0402:R_2k2_0402")
		(at 125.73 49.53 270)
		(unit 1)
		(exclude_from_sim no)
		(in_bom yes)
		(on_board yes)
		(dnp no)
		(fields_autoplaced yes)
		(property "Reference" "R362"
			(at 128.27 50.8 90)
			(effects
				(font
					(size 1.27 1.27)
					(thickness 0.15)
				)
				(justify left)
			)
		)
		(property "Value" "R_2k2_0402"
			(at 113.03 69.85 0)
			(effects
				(font
					(size 1.27 1.27)
					(thickness 0.15)
				)
				(justify left bottom)
				(hide yes)
			)
		)
		(property "Footprint" "antmicro-footprints:R_0402_1005Metric"
			(at 110.49 69.85 0)
			(effects
				(font
					(size 1.27 1.27)
					(thickness 0.15)
				)
				(justify left bottom)
				(hide yes)
			)
		)
		(property "Datasheet" "https://www.bourns.com/docs/product-datasheets/cr.pdf"
			(at 107.95 69.85 0)
			(effects
				(font
					(size 1.27 1.27)
					(thickness 0.15)
				)
				(justify left bottom)
				(hide yes)
			)
		)
		(property "Description" "SMD Chip Resistor, 2.2 kohm, ± 1%, 62.5 mW, 0402 [1005 Metric], Thick Film, General Purpose"
			(at 95.25 69.85 0)
			(effects
				(font
					(size 1.27 1.27)
				)
				(justify left bottom)
				(hide yes)
			)
		)
		(property "MPN" "CR0402-FX-2201GLF"
			(at 105.41 69.85 0)
			(effects
				(font
					(size 1.27 1.27)
					(thickness 0.15)
				)
				(justify left bottom)
				(hide yes)
			)
		)
		(property "Manufacturer" "Bourns"
			(at 102.87 69.85 0)
			(effects
				(font
					(size 1.27 1.27)
					(thickness 0.15)
				)
				(justify left bottom)
				(hide yes)
			)
		)
		(property "License" "Apache-2.0"
			(at 100.33 69.85 0)
			(effects
				(font
					(size 1.27 1.27)
					(thickness 0.15)
				)
				(justify left bottom)
				(hide yes)
			)
		)
		(property "Author" "Antmicro"
			(at 97.79 69.85 0)
			(effects
				(font
					(size 1.27 1.27)
					(thickness 0.15)
				)
				(justify left bottom)
				(hide yes)
			)
		)
		(property "Val" "2k2"
			(at 128.27 53.34 90)
			(effects
				(font
					(size 1.27 1.27)
					(thickness 0.15)
				)
				(justify left)
			)
		)
		(property "Tolerance" "1%"
			(at 115.57 69.85 0)
			(effects
				(font
					(size 1.27 1.27)
				)
				(justify left bottom)
				(hide yes)
			)
		)
		(pin "2"
		)
		(pin "1"
		)
		(instances
			(project "jetson-agx-thor-baseboard"
				(path ""
					(reference "R362")
					(unit 1)
				)
			)
		)
	)
	(symbol
		(lib_id "antmicroCapacitors0402:C_100n_0402")
		(at 100.33 91.44 270)
		(mirror x)
		(unit 1)
		(exclude_from_sim no)
		(in_bom yes)
		(on_board yes)
		(dnp no)
		(property "Reference" "C2"
			(at 102.235 87.63 90)
			(effects
				(font
					(size 1.27 1.27)
				)
				(justify left)
			)
		)
		(property "Value" "C_100n_0402"
			(at 90.17 71.12 0)
			(effects
				(font
					(size 1.27 1.27)
					(thickness 0.15)
				)
				(justify left bottom)
				(hide yes)
			)
		)
		(property "Footprint" "antmicro-footprints:C_0402_1005Metric"
			(at 87.63 71.12 0)
			(effects
				(font
					(size 1.27 1.27)
					(thickness 0.15)
				)
				(justify left bottom)
				(hide yes)
			)
		)
		(property "Datasheet" "https://www.murata.com/products/productdetail?partno=GRM155R61H104KE14%23"
			(at 85.09 71.12 0)
			(effects
				(font
					(size 1.27 1.27)
					(thickness 0.15)
				)
				(justify left bottom)
				(hide yes)
			)
		)
		(property "Description" "SMD Multilayer Ceramic Capacitor, 0.1 µF, 50 V, 0402 [1005 Metric], ± 10%, X5R, GRM Series"
			(at 100.33 91.44 0)
			(effects
				(font
					(size 1.27 1.27)
				)
				(hide yes)
			)
		)
		(property "Manufacturer" "Murata"
			(at 80.01 71.12 0)
			(effects
				(font
					(size 1.27 1.27)
					(thickness 0.15)
				)
				(justify left bottom)
				(hide yes)
			)
		)
		(property "MPN" "GRM155R61H104KE14D"
			(at 82.55 71.12 0)
			(effects
				(font
					(size 1.27 1.27)
					(thickness 0.15)
				)
				(justify left bottom)
				(hide yes)
			)
		)
		(property "Val" "100n"
			(at 102.235 90.17 90)
			(effects
				(font
					(size 1.27 1.27)
					(thickness 0.15)
				)
				(justify left)
			)
		)
		(property "License" "Apache-2.0"
			(at 77.47 71.12 0)
			(effects
				(font
					(size 1.27 1.27)
					(thickness 0.15)
				)
				(justify left bottom)
				(hide yes)
			)
		)
		(property "Author" "Antmicro"
			(at 74.93 71.12 0)
			(effects
				(font
					(size 1.27 1.27)
					(thickness 0.15)
				)
				(justify left bottom)
				(hide yes)
			)
		)
		(property "Voltage" "50V"
			(at 72.39 71.12 0)
			(effects
				(font
					(size 1.27 1.27)
				)
				(justify left bottom)
				(hide yes)
			)
		)
		(property "Dielectric" "X5R"
			(at 69.85 71.12 0)
			(effects
				(font
					(size 1.27 1.27)
				)
				(justify left bottom)
				(hide yes)
			)
		)
		(pin "1"
		)
		(pin "2"
		)
		(instances
			(project "jetson-agx-thor-baseboard"
				(path ""
					(reference "C2")
					(unit 1)
				)
			)
		)
	)
	(symbol
		(lib_id "antmicroCapacitors0402:C_100n_0402")
		(at 77.47 146.05 270)
		(mirror x)
		(unit 1)
		(exclude_from_sim no)
		(in_bom yes)
		(on_board yes)
		(dnp no)
		(property "Reference" "C216"
			(at 75.565 142.24 90)
			(effects
				(font
					(size 1.27 1.27)
				)
				(justify right)
			)
		)
		(property "Value" "C_100n_0402"
			(at 67.31 125.73 0)
			(effects
				(font
					(size 1.27 1.27)
					(thickness 0.15)
				)
				(justify left bottom)
				(hide yes)
			)
		)
		(property "Footprint" "antmicro-footprints:C_0402_1005Metric"
			(at 64.77 125.73 0)
			(effects
				(font
					(size 1.27 1.27)
					(thickness 0.15)
				)
				(justify left bottom)
				(hide yes)
			)
		)
		(property "Datasheet" "https://www.murata.com/products/productdetail?partno=GRM155R61H104KE14%23"
			(at 62.23 125.73 0)
			(effects
				(font
					(size 1.27 1.27)
					(thickness 0.15)
				)
				(justify left bottom)
				(hide yes)
			)
		)
		(property "Description" "SMD Multilayer Ceramic Capacitor, 0.1 µF, 50 V, 0402 [1005 Metric], ± 10%, X5R, GRM Series"
			(at 77.47 146.05 0)
			(effects
				(font
					(size 1.27 1.27)
				)
				(hide yes)
			)
		)
		(property "Manufacturer" "Murata"
			(at 57.15 125.73 0)
			(effects
				(font
					(size 1.27 1.27)
					(thickness 0.15)
				)
				(justify left bottom)
				(hide yes)
			)
		)
		(property "MPN" "GRM155R61H104KE14D"
			(at 59.69 125.73 0)
			(effects
				(font
					(size 1.27 1.27)
					(thickness 0.15)
				)
				(justify left bottom)
				(hide yes)
			)
		)
		(property "Val" "100n"
			(at 75.565 144.78 90)
			(effects
				(font
					(size 1.27 1.27)
					(thickness 0.15)
				)
				(justify right)
			)
		)
		(property "License" "Apache-2.0"
			(at 54.61 125.73 0)
			(effects
				(font
					(size 1.27 1.27)
					(thickness 0.15)
				)
				(justify left bottom)
				(hide yes)
			)
		)
		(property "Author" "Antmicro"
			(at 52.07 125.73 0)
			(effects
				(font
					(size 1.27 1.27)
					(thickness 0.15)
				)
				(justify left bottom)
				(hide yes)
			)
		)
		(property "Voltage" "50V"
			(at 49.53 125.73 0)
			(effects
				(font
					(size 1.27 1.27)
				)
				(justify left bottom)
				(hide yes)
			)
		)
		(property "Dielectric" "X5R"
			(at 46.99 125.73 0)
			(effects
				(font
					(size 1.27 1.27)
				)
				(justify left bottom)
				(hide yes)
			)
		)
		(pin "1"
		)
		(pin "2"
		)
		(instances
			(project "jetson-agx-thor-baseboard"
				(path ""
					(reference "C216")
					(unit 1)
				)
			)
		)
	)
	(symbol
		(lib_id "antmicropower:+3V3")
		(at 100.33 34.29 0)
		(unit 1)
		(exclude_from_sim no)
		(in_bom yes)
		(on_board yes)
		(dnp no)
		(property "Reference" "#PWR026"
			(at 100.33 38.1 0)
			(effects
				(font
					(size 1.27 1.27)
				)
				(justify left bottom)
				(hide yes)
			)
		)
		(property "Value" "+3V3"
			(at 97.155 30.48 0)
			(effects
				(font
					(size 1.27 1.27)
					(thickness 0.15)
				)
				(justify left)
			)
		)
		(property "Footprint" ""
			(at 115.57 41.91 0)
			(effects
				(font
					(size 1.27 1.27)
					(thickness 0.15)
				)
				(justify left bottom)
				(hide yes)
			)
		)
		(property "Datasheet" ""
			(at 115.57 44.45 0)
			(effects
				(font
					(size 1.27 1.27)
					(thickness 0.15)
				)
				(justify left bottom)
				(hide yes)
			)
		)
		(property "Description" ""
			(at 100.33 34.29 0)
			(effects
				(font
					(size 1.27 1.27)
				)
				(hide yes)
			)
		)
		(property "Author" "Antmicro"
			(at 115.57 36.83 0)
			(effects
				(font
					(size 1.27 1.27)
					(thickness 0.15)
				)
				(justify left bottom)
				(hide yes)
			)
		)
		(property "License" "Apache-2.0"
			(at 115.57 39.37 0)
			(effects
				(font
					(size 1.27 1.27)
					(thickness 0.15)
				)
				(justify left bottom)
				(hide yes)
			)
		)
		(pin "1"
		)
		(instances
			(project "jetson-agx-thor-baseboard"
				(path ""
					(reference "#PWR026")
					(unit 1)
				)
			)
		)
	)
	(symbol
		(lib_id "antmicropower:GND")
		(at 100.33 41.91 0)
		(unit 1)
		(exclude_from_sim no)
		(in_bom yes)
		(on_board yes)
		(dnp no)
		(property "Reference" "#PWR0489"
			(at 100.33 48.26 0)
			(effects
				(font
					(size 1.27 1.27)
				)
				(justify left bottom)
				(hide yes)
			)
		)
		(property "Value" "GND"
			(at 100.33 45.72 0)
			(effects
				(font
					(size 1.27 1.27)
					(thickness 0.15)
				)
			)
		)
		(property "Footprint" ""
			(at 109.22 49.53 0)
			(effects
				(font
					(size 1.27 1.27)
					(thickness 0.15)
				)
				(justify left bottom)
				(hide yes)
			)
		)
		(property "Datasheet" ""
			(at 109.22 54.61 0)
			(effects
				(font
					(size 1.27 1.27)
					(thickness 0.15)
				)
				(justify left bottom)
				(hide yes)
			)
		)
		(property "Description" ""
			(at 100.33 41.91 0)
			(effects
				(font
					(size 1.27 1.27)
				)
				(hide yes)
			)
		)
		(property "Author" "Antmicro"
			(at 109.22 49.53 0)
			(effects
				(font
					(size 1.27 1.27)
					(thickness 0.15)
				)
				(justify left bottom)
				(hide yes)
			)
		)
		(property "License" "Apache-2.0"
			(at 109.22 52.07 0)
			(effects
				(font
					(size 1.27 1.27)
					(thickness 0.15)
				)
				(justify left bottom)
				(hide yes)
			)
		)
		(pin "1"
		)
		(instances
			(project "jetson-agx-thor-baseboard"
				(path ""
					(reference "#PWR0489")
					(unit 1)
				)
			)
		)
	)
	(symbol
		(lib_id "antmicroTestPoints:TP_0.75mm_SMD")
		(at 373.38 66.04 0)
		(unit 1)
		(exclude_from_sim no)
		(in_bom no)
		(on_board yes)
		(dnp no)
		(property "Reference" "TP107"
			(at 377.698 66.04 0)
			(effects
				(font
					(size 1.27 1.27)
				)
				(justify left)
			)
		)
		(property "Value" "TP_0.75mm_SMD"
			(at 383.54 69.85 0)
			(effects
				(font
					(size 1.27 1.27)
					(thickness 0.15)
				)
				(justify left bottom)
				(hide yes)
			)
		)
		(property "Footprint" "antmicro-footprints:TP_SMD_0.75mm"
			(at 383.54 72.39 0)
			(effects
				(font
					(size 1.27 1.27)
					(thickness 0.15)
				)
				(justify left bottom)
				(hide yes)
			)
		)
		(property "Datasheet" ""
			(at 391.16 78.74 0)
			(effects
				(font
					(size 1.27 1.27)
					(thickness 0.15)
				)
				(justify left bottom)
				(hide yes)
			)
		)
		(property "Description" "SMT test point"
			(at 373.38 66.04 0)
			(effects
				(font
					(size 1.27 1.27)
				)
				(hide yes)
			)
		)
		(property "MPN" ""
			(at 384.175 77.47 0)
			(effects
				(font
					(size 1.27 1.27)
					(thickness 0.15)
				)
				(justify left bottom)
				(hide yes)
			)
		)
		(property "Manufacturer" ""
			(at 384.175 72.39 0)
			(effects
				(font
					(size 1.27 1.27)
					(thickness 0.15)
				)
				(justify left bottom)
				(hide yes)
			)
		)
		(property "Author" "Antmicro"
			(at 383.54 74.93 0)
			(effects
				(font
					(size 1.27 1.27)
					(thickness 0.15)
				)
				(justify left bottom)
				(hide yes)
			)
		)
		(property "License" "Apache-2.0"
			(at 383.54 77.47 0)
			(effects
				(font
					(size 1.27 1.27)
					(thickness 0.15)
				)
				(justify left bottom)
				(hide yes)
			)
		)
		(pin "1"
		)
		(instances
			(project "jetson-agx-thor-baseboard"
				(path ""
					(reference "TP107")
					(unit 1)
				)
			)
		)
	)
	(symbol
		(lib_id "antmicroResistors0402:R_2k2_0402")
		(at 146.05 49.53 270)
		(unit 1)
		(exclude_from_sim no)
		(in_bom yes)
		(on_board yes)
		(dnp no)
		(fields_autoplaced yes)
		(property "Reference" "R374"
			(at 148.59 50.8 90)
			(effects
				(font
					(size 1.27 1.27)
					(thickness 0.15)
				)
				(justify left)
			)
		)
		(property "Value" "R_2k2_0402"
			(at 133.35 69.85 0)
			(effects
				(font
					(size 1.27 1.27)
					(thickness 0.15)
				)
				(justify left bottom)
				(hide yes)
			)
		)
		(property "Footprint" "antmicro-footprints:R_0402_1005Metric"
			(at 130.81 69.85 0)
			(effects
				(font
					(size 1.27 1.27)
					(thickness 0.15)
				)
				(justify left bottom)
				(hide yes)
			)
		)
		(property "Datasheet" "https://www.bourns.com/docs/product-datasheets/cr.pdf"
			(at 128.27 69.85 0)
			(effects
				(font
					(size 1.27 1.27)
					(thickness 0.15)
				)
				(justify left bottom)
				(hide yes)
			)
		)
		(property "Description" "SMD Chip Resistor, 2.2 kohm, ± 1%, 62.5 mW, 0402 [1005 Metric], Thick Film, General Purpose"
			(at 115.57 69.85 0)
			(effects
				(font
					(size 1.27 1.27)
				)
				(justify left bottom)
				(hide yes)
			)
		)
		(property "MPN" "CR0402-FX-2201GLF"
			(at 125.73 69.85 0)
			(effects
				(font
					(size 1.27 1.27)
					(thickness 0.15)
				)
				(justify left bottom)
				(hide yes)
			)
		)
		(property "Manufacturer" "Bourns"
			(at 123.19 69.85 0)
			(effects
				(font
					(size 1.27 1.27)
					(thickness 0.15)
				)
				(justify left bottom)
				(hide yes)
			)
		)
		(property "License" "Apache-2.0"
			(at 120.65 69.85 0)
			(effects
				(font
					(size 1.27 1.27)
					(thickness 0.15)
				)
				(justify left bottom)
				(hide yes)
			)
		)
		(property "Author" "Antmicro"
			(at 118.11 69.85 0)
			(effects
				(font
					(size 1.27 1.27)
					(thickness 0.15)
				)
				(justify left bottom)
				(hide yes)
			)
		)
		(property "Val" "2k2"
			(at 148.59 53.34 90)
			(effects
				(font
					(size 1.27 1.27)
					(thickness 0.15)
				)
				(justify left)
			)
		)
		(property "Tolerance" "1%"
			(at 135.89 69.85 0)
			(effects
				(font
					(size 1.27 1.27)
				)
				(justify left bottom)
				(hide yes)
			)
		)
		(pin "2"
		)
		(pin "1"
		)
		(instances
			(project "jetson-agx-thor-baseboard"
				(path ""
					(reference "R374")
					(unit 1)
				)
			)
		)
	)
	(symbol
		(lib_id "antmicroCapacitors0402:C_100n_0402")
		(at 77.47 209.55 270)
		(mirror x)
		(unit 1)
		(exclude_from_sim no)
		(in_bom yes)
		(on_board yes)
		(dnp no)
		(property "Reference" "C354"
			(at 75.565 205.74 90)
			(effects
				(font
					(size 1.27 1.27)
				)
				(justify right)
			)
		)
		(property "Value" "C_100n_0402"
			(at 67.31 189.23 0)
			(effects
				(font
					(size 1.27 1.27)
					(thickness 0.15)
				)
				(justify left bottom)
				(hide yes)
			)
		)
		(property "Footprint" "antmicro-footprints:C_0402_1005Metric"
			(at 64.77 189.23 0)
			(effects
				(font
					(size 1.27 1.27)
					(thickness 0.15)
				)
				(justify left bottom)
				(hide yes)
			)
		)
		(property "Datasheet" "https://www.murata.com/products/productdetail?partno=GRM155R61H104KE14%23"
			(at 62.23 189.23 0)
			(effects
				(font
					(size 1.27 1.27)
					(thickness 0.15)
				)
				(justify left bottom)
				(hide yes)
			)
		)
		(property "Description" "SMD Multilayer Ceramic Capacitor, 0.1 µF, 50 V, 0402 [1005 Metric], ± 10%, X5R, GRM Series"
			(at 77.47 209.55 0)
			(effects
				(font
					(size 1.27 1.27)
				)
				(hide yes)
			)
		)
		(property "Manufacturer" "Murata"
			(at 57.15 189.23 0)
			(effects
				(font
					(size 1.27 1.27)
					(thickness 0.15)
				)
				(justify left bottom)
				(hide yes)
			)
		)
		(property "MPN" "GRM155R61H104KE14D"
			(at 59.69 189.23 0)
			(effects
				(font
					(size 1.27 1.27)
					(thickness 0.15)
				)
				(justify left bottom)
				(hide yes)
			)
		)
		(property "Val" "100n"
			(at 75.565 208.28 90)
			(effects
				(font
					(size 1.27 1.27)
					(thickness 0.15)
				)
				(justify right)
			)
		)
		(property "License" "Apache-2.0"
			(at 54.61 189.23 0)
			(effects
				(font
					(size 1.27 1.27)
					(thickness 0.15)
				)
				(justify left bottom)
				(hide yes)
			)
		)
		(property "Author" "Antmicro"
			(at 52.07 189.23 0)
			(effects
				(font
					(size 1.27 1.27)
					(thickness 0.15)
				)
				(justify left bottom)
				(hide yes)
			)
		)
		(property "Voltage" "50V"
			(at 49.53 189.23 0)
			(effects
				(font
					(size 1.27 1.27)
				)
				(justify left bottom)
				(hide yes)
			)
		)
		(property "Dielectric" "X5R"
			(at 46.99 189.23 0)
			(effects
				(font
					(size 1.27 1.27)
				)
				(justify left bottom)
				(hide yes)
			)
		)
		(pin "1"
		)
		(pin "2"
		)
		(instances
			(project "jetson-agx-thor-baseboard"
				(path ""
					(reference "C354")
					(unit 1)
				)
			)
		)
	)
	(symbol
		(lib_id "antmicroTestPoints:TP_0.75mm_SMD")
		(at 373.38 68.58 0)
		(unit 1)
		(exclude_from_sim no)
		(in_bom no)
		(on_board yes)
		(dnp no)
		(property "Reference" "TP108"
			(at 377.698 68.58 0)
			(effects
				(font
					(size 1.27 1.27)
				)
				(justify left)
			)
		)
		(property "Value" "TP_0.75mm_SMD"
			(at 383.54 72.39 0)
			(effects
				(font
					(size 1.27 1.27)
					(thickness 0.15)
				)
				(justify left bottom)
				(hide yes)
			)
		)
		(property "Footprint" "antmicro-footprints:TP_SMD_0.75mm"
			(at 383.54 74.93 0)
			(effects
				(font
					(size 1.27 1.27)
					(thickness 0.15)
				)
				(justify left bottom)
				(hide yes)
			)
		)
		(property "Datasheet" ""
			(at 391.16 81.28 0)
			(effects
				(font
					(size 1.27 1.27)
					(thickness 0.15)
				)
				(justify left bottom)
				(hide yes)
			)
		)
		(property "Description" "SMT test point"
			(at 373.38 68.58 0)
			(effects
				(font
					(size 1.27 1.27)
				)
				(hide yes)
			)
		)
		(property "MPN" ""
			(at 384.175 80.01 0)
			(effects
				(font
					(size 1.27 1.27)
					(thickness 0.15)
				)
				(justify left bottom)
				(hide yes)
			)
		)
		(property "Manufacturer" ""
			(at 384.175 74.93 0)
			(effects
				(font
					(size 1.27 1.27)
					(thickness 0.15)
				)
				(justify left bottom)
				(hide yes)
			)
		)
		(property "Author" "Antmicro"
			(at 383.54 77.47 0)
			(effects
				(font
					(size 1.27 1.27)
					(thickness 0.15)
				)
				(justify left bottom)
				(hide yes)
			)
		)
		(property "License" "Apache-2.0"
			(at 383.54 80.01 0)
			(effects
				(font
					(size 1.27 1.27)
					(thickness 0.15)
				)
				(justify left bottom)
				(hide yes)
			)
		)
		(pin "1"
		)
		(instances
			(project "jetson-agx-thor-baseboard"
				(path ""
					(reference "TP108")
					(unit 1)
				)
			)
		)
	)
	(symbol
		(lib_id "antmicroResistors0402:R_2k2_0402")
		(at 41.91 101.6 270)
		(unit 1)
		(exclude_from_sim no)
		(in_bom no)
		(on_board yes)
		(dnp yes)
		(fields_autoplaced yes)
		(property "Reference" "R228"
			(at 44.45 102.87 90)
			(effects
				(font
					(size 1.27 1.27)
					(thickness 0.15)
				)
				(justify left)
			)
		)
		(property "Value" "R_2k2_0402"
			(at 29.21 121.92 0)
			(effects
				(font
					(size 1.27 1.27)
					(thickness 0.15)
				)
				(justify left bottom)
				(hide yes)
			)
		)
		(property "Footprint" "antmicro-footprints:R_0402_1005Metric"
			(at 26.67 121.92 0)
			(effects
				(font
					(size 1.27 1.27)
					(thickness 0.15)
				)
				(justify left bottom)
				(hide yes)
			)
		)
		(property "Datasheet" "https://www.bourns.com/docs/product-datasheets/cr.pdf"
			(at 24.13 121.92 0)
			(effects
				(font
					(size 1.27 1.27)
					(thickness 0.15)
				)
				(justify left bottom)
				(hide yes)
			)
		)
		(property "Description" "SMD Chip Resistor, 2.2 kohm, ± 1%, 62.5 mW, 0402 [1005 Metric], Thick Film, General Purpose"
			(at 11.43 121.92 0)
			(effects
				(font
					(size 1.27 1.27)
				)
				(justify left bottom)
				(hide yes)
			)
		)
		(property "MPN" "CR0402-FX-2201GLF"
			(at 21.59 121.92 0)
			(effects
				(font
					(size 1.27 1.27)
					(thickness 0.15)
				)
				(justify left bottom)
				(hide yes)
			)
		)
		(property "Manufacturer" "Bourns"
			(at 19.05 121.92 0)
			(effects
				(font
					(size 1.27 1.27)
					(thickness 0.15)
				)
				(justify left bottom)
				(hide yes)
			)
		)
		(property "License" "Apache-2.0"
			(at 16.51 121.92 0)
			(effects
				(font
					(size 1.27 1.27)
					(thickness 0.15)
				)
				(justify left bottom)
				(hide yes)
			)
		)
		(property "Author" "Antmicro"
			(at 13.97 121.92 0)
			(effects
				(font
					(size 1.27 1.27)
					(thickness 0.15)
				)
				(justify left bottom)
				(hide yes)
			)
		)
		(property "Val" "2k2"
			(at 44.45 105.41 90)
			(effects
				(font
					(size 1.27 1.27)
					(thickness 0.15)
				)
				(justify left)
			)
		)
		(property "Tolerance" "1%"
			(at 31.75 121.92 0)
			(effects
				(font
					(size 1.27 1.27)
				)
				(justify left bottom)
				(hide yes)
			)
		)
		(pin "2"
		)
		(pin "1"
		)
		(instances
			(project ""
				(path ""
					(reference "R228")
					(unit 1)
				)
			)
		)
	)
	(symbol
		(lib_id "antmicroTestPoints:TP_0.75mm_SMD")
		(at 307.34 219.71 0)
		(mirror y)
		(unit 1)
		(exclude_from_sim no)
		(in_bom no)
		(on_board yes)
		(dnp no)
		(property "Reference" "TP102"
			(at 303.022 219.71 0)
			(effects
				(font
					(size 1.27 1.27)
				)
				(justify left)
			)
		)
		(property "Value" "TP_0.75mm_SMD"
			(at 297.18 223.52 0)
			(effects
				(font
					(size 1.27 1.27)
					(thickness 0.15)
				)
				(justify left bottom)
				(hide yes)
			)
		)
		(property "Footprint" "antmicro-footprints:TP_SMD_0.75mm"
			(at 297.18 226.06 0)
			(effects
				(font
					(size 1.27 1.27)
					(thickness 0.15)
				)
				(justify left bottom)
				(hide yes)
			)
		)
		(property "Datasheet" ""
			(at 289.56 232.41 0)
			(effects
				(font
					(size 1.27 1.27)
					(thickness 0.15)
				)
				(justify left bottom)
				(hide yes)
			)
		)
		(property "Description" "SMT test point"
			(at 307.34 219.71 0)
			(effects
				(font
					(size 1.27 1.27)
				)
				(hide yes)
			)
		)
		(property "MPN" ""
			(at 296.545 231.14 0)
			(effects
				(font
					(size 1.27 1.27)
					(thickness 0.15)
				)
				(justify left bottom)
				(hide yes)
			)
		)
		(property "Manufacturer" ""
			(at 296.545 226.06 0)
			(effects
				(font
					(size 1.27 1.27)
					(thickness 0.15)
				)
				(justify left bottom)
				(hide yes)
			)
		)
		(property "Author" "Antmicro"
			(at 297.18 228.6 0)
			(effects
				(font
					(size 1.27 1.27)
					(thickness 0.15)
				)
				(justify left bottom)
				(hide yes)
			)
		)
		(property "License" "Apache-2.0"
			(at 297.18 231.14 0)
			(effects
				(font
					(size 1.27 1.27)
					(thickness 0.15)
				)
				(justify left bottom)
				(hide yes)
			)
		)
		(pin "1"
		)
		(instances
			(project "jetson-agx-thor-baseboard"
				(path ""
					(reference "TP102")
					(unit 1)
				)
			)
		)
	)
	(symbol
		(lib_id "antmicroB2BConnectors:Hermaphroditic_Molex_203456-0003_CUSTOM_Jetson_AGX_Thor_H8mm")
		(at 214.63 35.56 0)
		(unit 11)
		(exclude_from_sim no)
		(in_bom yes)
		(on_board yes)
		(dnp no)
		(fields_autoplaced yes)
		(property "Reference" "J1"
			(at 227.33 29.21 0)
			(effects
				(font
					(size 1.27 1.27)
				)
			)
		)
		(property "Value" "Hermaphroditic_Molex_203456-0003_CUSTOM_Jetson_AGX_Thor_H8mm"
			(at 291.084 41.656 0)
			(effects
				(font
					(size 1.27 1.27)
				)
				(justify left bottom)
				(hide yes)
			)
		)
		(property "Footprint" "antmicro-footprints:Conn_Hermaphroditic_Molex_203456-0003_mirrored"
			(at 291.084 43.942 0)
			(effects
				(font
					(size 1.27 1.27)
				)
				(justify left bottom)
				(hide yes)
			)
		)
		(property "Datasheet" "https://www.molex.com/content/dam/molex/molex-dot-com/products/automated/en-us/salesdrawingpdf/203/203456/2034560003_sd.pdf?inline"
			(at 291.084 46.228 0)
			(effects
				(font
					(size 1.27 1.27)
				)
				(justify left bottom)
				(hide yes)
			)
		)
		(property "Description" "Mirror Mezz Hermaphroditic Connector, 5.50mm Connector Height, BGA-Attach Mounting, 7 Pair, 11 Row, 699 Circuits, 0.76µm Gold Plating, without Pegs"
			(at 291.084 54.864 0)
			(effects
				(font
					(size 1.27 1.27)
				)
				(justify left bottom)
				(hide yes)
			)
		)
		(property "MPN" "203456-0003"
			(at 227.33 31.75 0)
			(effects
				(font
					(size 1.27 1.27)
				)
			)
		)
		(property "Manufacturer" "Molex"
			(at 291.084 48.514 0)
			(effects
				(font
					(size 1.27 1.27)
				)
				(justify left bottom)
				(hide yes)
			)
		)
		(property "Author" "Antmicro"
			(at 291.084 50.546 0)
			(effects
				(font
					(size 1.27 1.27)
				)
				(justify left bottom)
				(hide yes)
			)
		)
		(property "License" "Apache-2.0"
			(at 291.084 52.578 0)
			(effects
				(font
					(size 1.27 1.27)
				)
				(justify left bottom)
				(hide yes)
			)
		)
		(pin "F63"
		)
		(pin "L33"
		)
		(pin "H2"
		)
		(pin "A20"
		)
		(pin "C33"
		)
		(pin "B4"
		)
		(pin "L63"
		)
		(pin "A21"
		)
		(pin "A17"
		)
		(pin "C29"
		)
		(pin "D18"
		)
		(pin "C49"
		)
		(pin "B57"
		)
		(pin "L35"
		)
		(pin "C43"
		)
		(pin "C9"
		)
		(pin "J65"
		)
		(pin "D15"
		)
		(pin "C20"
		)
		(pin "C52"
		)
		(pin "C3"
		)
		(pin "L31"
		)
		(pin "C28"
		)
		(pin "B50"
		)
		(pin "B26"
		)
		(pin "B23"
		)
		(pin "B15"
		)
		(pin "B27"
		)
		(pin "C21"
		)
		(pin "B44"
		)
		(pin "B18"
		)
		(pin "J63"
		)
		(pin "C32"
		)
		(pin "F1"
		)
		(pin "G16"
		)
		(pin "F47"
		)
		(pin "H65"
		)
		(pin "E40"
		)
		(pin "F14"
		)
		(pin "B7"
		)
		(pin "E29"
		)
		(pin "E25"
		)
		(pin "A63"
		)
		(pin "F38"
		)
		(pin "D14"
		)
		(pin "F35"
		)
		(pin "F41"
		)
		(pin "F19"
		)
		(pin "F15"
		)
		(pin "E52"
		)
		(pin "F44"
		)
		(pin "E3"
		)
		(pin "E36"
		)
		(pin "G20"
		)
		(pin "H15"
		)
		(pin "G62"
		)
		(pin "L40"
		)
		(pin "G12"
		)
		(pin "C62"
		)
		(pin "B22"
		)
		(pin "D19"
		)
		(pin "B41"
		)
		(pin "B30"
		)
		(pin "H28"
		)
		(pin "H29"
		)
		(pin "B3"
		)
		(pin "L58"
		)
		(pin "D20"
		)
		(pin "B29"
		)
		(pin "B28"
		)
		(pin "C46"
		)
		(pin "A16"
		)
		(pin "C25"
		)
		(pin "J60"
		)
		(pin "C12"
		)
		(pin "C16"
		)
		(pin "B34"
		)
		(pin "E16"
		)
		(pin "B19"
		)
		(pin "E49"
		)
		(pin "B14"
		)
		(pin "B35"
		)
		(pin "F34"
		)
		(pin "E12"
		)
		(pin "E13"
		)
		(pin "A13"
		)
		(pin "E64"
		)
		(pin "F7"
		)
		(pin "G21"
		)
		(pin "F4"
		)
		(pin "F27"
		)
		(pin "E57"
		)
		(pin "F23"
		)
		(pin "E32"
		)
		(pin "E43"
		)
		(pin "E33"
		)
		(pin "G17"
		)
		(pin "B39"
		)
		(pin "A9"
		)
		(pin "L38"
		)
		(pin "C13"
		)
		(pin "F18"
		)
		(pin "E9"
		)
		(pin "H14"
		)
		(pin "L7"
		)
		(pin "H39"
		)
		(pin "D57"
		)
		(pin "A30"
		)
		(pin "A31"
		)
		(pin "F62"
		)
		(pin "E62"
		)
		(pin "A43"
		)
		(pin "E28"
		)
		(pin "H60"
		)
		(pin "D41"
		)
		(pin "E24"
		)
		(pin "E37"
		)
		(pin "D39"
		)
		(pin "L26"
		)
		(pin "L39"
		)
		(pin "G3"
		)
		(pin "F11"
		)
		(pin "D1"
		)
		(pin "D11"
		)
		(pin "L22"
		)
		(pin "D21"
		)
		(pin "J22"
		)
		(pin "J23"
		)
		(pin "F3"
		)
		(pin "H23"
		)
		(pin "L21"
		)
		(pin "C11"
		)
		(pin "C10"
		)
		(pin "L25"
		)
		(pin "K57"
		)
		(pin "E54"
		)
		(pin "K62"
		)
		(pin "E58"
		)
		(pin "E4"
		)
		(pin "F5"
		)
		(pin "F6"
		)
		(pin "A26"
		)
		(pin "A27"
		)
		(pin "B54"
		)
		(pin "A54"
		)
		(pin "C4"
		)
		(pin "D5"
		)
		(pin "L20"
		)
		(pin "L54"
		)
		(pin "K25"
		)
		(pin "K24"
		)
		(pin "K29"
		)
		(pin "K28"
		)
		(pin "G29"
		)
		(pin "E55"
		)
		(pin "B56"
		)
		(pin "J57"
		)
		(pin "B55"
		)
		(pin "K13"
		)
		(pin "K12"
		)
		(pin "G35"
		)
		(pin "G34"
		)
		(pin "D12"
		)
		(pin "L4"
		)
		(pin "L6"
		)
		(pin "L5"
		)
		(pin "H6"
		)
		(pin "G40"
		)
		(pin "G1"
		)
		(pin "H27"
		)
		(pin "C57"
		)
		(pin "E56"
		)
		(pin "F55"
		)
		(pin "J55"
		)
		(pin "A47"
		)
		(pin "J62"
		)
		(pin "J11"
		)
		(pin "E27"
		)
		(pin "H34"
		)
		(pin "A56"
		)
		(pin "D55"
		)
		(pin "D60"
		)
		(pin "C51"
		)
		(pin "C50"
		)
		(pin "A24"
		)
		(pin "A15"
		)
		(pin "A14"
		)
		(pin "H45"
		)
		(pin "B45"
		)
		(pin "B46"
		)
		(pin "L45"
		)
		(pin "J50"
		)
		(pin "A48"
		)
		(pin "H55"
		)
		(pin "L3"
		)
		(pin "L46"
		)
		(pin "G13"
		)
		(pin "C38"
		)
		(pin "A18"
		)
		(pin "F56"
		)
		(pin "A39"
		)
		(pin "J40"
		)
		(pin "L48"
		)
		(pin "J54"
		)
		(pin "H53"
		)
		(pin "H4"
		)
		(pin "D31"
		)
		(pin "C55"
		)
		(pin "H63"
		)
		(pin "H32"
		)
		(pin "H33"
		)
		(pin "L29"
		)
		(pin "D42"
		)
		(pin "D43"
		)
		(pin "D46"
		)
		(pin "C39"
		)
		(pin "A58"
		)
		(pin "B58"
		)
		(pin "H52"
		)
		(pin "F39"
		)
		(pin "A49"
		)
		(pin "F22"
		)
		(pin "G24"
		)
		(pin "E21"
		)
		(pin "F31"
		)
		(pin "D34"
		)
		(pin "C40"
		)
		(pin "C24"
		)
		(pin "C36"
		)
		(pin "C37"
		)
		(pin "B11"
		)
		(pin "C17"
		)
		(pin "K27"
		)
		(pin "G28"
		)
		(pin "D3"
		)
		(pin "H12"
		)
		(pin "H13"
		)
		(pin "J37"
		)
		(pin "D30"
		)
		(pin "D50"
		)
		(pin "A61"
		)
		(pin "D37"
		)
		(pin "G59"
		)
		(pin "F2"
		)
		(pin "D44"
		)
		(pin "J3"
		)
		(pin "H18"
		)
		(pin "H19"
		)
		(pin "A33"
		)
		(pin "H11"
		)
		(pin "A46"
		)
		(pin "L17"
		)
		(pin "G33"
		)
		(pin "D64"
		)
		(pin "L56"
		)
		(pin "B32"
		)
		(pin "G7"
		)
		(pin "L15"
		)
		(pin "F10"
		)
		(pin "F9"
		)
		(pin "G63"
		)
		(pin "J28"
		)
		(pin "G46"
		)
		(pin "C35"
		)
		(pin "G25"
		)
		(pin "H43"
		)
		(pin "H42"
		)
		(pin "D13"
		)
		(pin "K37"
		)
		(pin "K22"
		)
		(pin "A23"
		)
		(pin "D9"
		)
		(pin "B5"
		)
		(pin "K7"
		)
		(pin "K39"
		)
		(pin "K52"
		)
		(pin "K51"
		)
		(pin "E6"
		)
		(pin "E7"
		)
		(pin "G41"
		)
		(pin "G42"
		)
		(pin "J41"
		)
		(pin "H7"
		)
		(pin "L10"
		)
		(pin "F16"
		)
		(pin "F17"
		)
		(pin "F20"
		)
		(pin "F21"
		)
		(pin "J42"
		)
		(pin "B43"
		)
		(pin "B42"
		)
		(pin "C23"
		)
		(pin "C65"
		)
		(pin "K58"
		)
		(pin "H57"
		)
		(pin "J58"
		)
		(pin "H58"
		)
		(pin "G15"
		)
		(pin "G14"
		)
		(pin "B16"
		)
		(pin "B17"
		)
		(pin "K32"
		)
		(pin "K33"
		)
		(pin "K45"
		)
		(pin "F50"
		)
		(pin "L30"
		)
		(pin "F32"
		)
		(pin "F33"
		)
		(pin "A29"
		)
		(pin "E60"
		)
		(pin "A53"
		)
		(pin "L27"
		)
		(pin "J12"
		)
		(pin "H50"
		)
		(pin "K40"
		)
		(pin "L42"
		)
		(pin "G32"
		)
		(pin "E65"
		)
		(pin "F26"
		)
		(pin "B47"
		)
		(pin "J46"
		)
		(pin "F24"
		)
		(pin "F25"
		)
		(pin "L16"
		)
		(pin "C48"
		)
		(pin "F40"
		)
		(pin "D40"
		)
		(pin "H40"
		)
		(pin "E59"
		)
		(pin "F59"
		)
		(pin "A38"
		)
		(pin "E5"
		)
		(pin "B25"
		)
		(pin "B24"
		)
		(pin "D63"
		)
		(pin "C7"
		)
		(pin "H8"
		)
		(pin "G4"
		)
		(pin "H44"
		)
		(pin "H41"
		)
		(pin "K4"
		)
		(pin "J30"
		)
		(pin "J31"
		)
		(pin "K41"
		)
		(pin "D22"
		)
		(pin "D23"
		)
		(pin "B31"
		)
		(pin "L23"
		)
		(pin "H24"
		)
		(pin "H25"
		)
		(pin "K11"
		)
		(pin "J56"
		)
		(pin "H30"
		)
		(pin "K30"
		)
		(pin "L60"
		)
		(pin "H22"
		)
		(pin "A28"
		)
		(pin "A25"
		)
		(pin "J32"
		)
		(pin "D26"
		)
		(pin "B10"
		)
		(pin "K31"
		)
		(pin "J33"
		)
		(pin "J21"
		)
		(pin "G27"
		)
		(pin "G26"
		)
		(pin "J35"
		)
		(pin "J34"
		)
		(pin "A34"
		)
		(pin "A35"
		)
		(pin "E1"
		)
		(pin "G43"
		)
		(pin "E10"
		)
		(pin "C5"
		)
		(pin "B8"
		)
		(pin "L47"
		)
		(pin "K3"
		)
		(pin "C64"
		)
		(pin "D27"
		)
		(pin "K23"
		)
		(pin "L59"
		)
		(pin "L43"
		)
		(pin "C2"
		)
		(pin "F12"
		)
		(pin "F13"
		)
		(pin "C63"
		)
		(pin "B63"
		)
		(pin "E23"
		)
		(pin "E22"
		)
		(pin "C1"
		)
		(pin "J5"
		)
		(pin "J6"
		)
		(pin "J7"
		)
		(pin "J19"
		)
		(pin "E53"
		)
		(pin "D61"
		)
		(pin "J36"
		)
		(pin "K53"
		)
		(pin "K54"
		)
		(pin "G58"
		)
		(pin "A57"
		)
		(pin "B20"
		)
		(pin "H64"
		)
		(pin "B13"
		)
		(pin "D33"
		)
		(pin "D32"
		)
		(pin "K42"
		)
		(pin "G6"
		)
		(pin "J18"
		)
		(pin "H5"
		)
		(pin "K6"
		)
		(pin "E15"
		)
		(pin "E14"
		)
		(pin "E26"
		)
		(pin "F52"
		)
		(pin "A22"
		)
		(pin "J14"
		)
		(pin "J15"
		)
		(pin "J43"
		)
		(pin "K18"
		)
		(pin "C22"
		)
		(pin "B51"
		)
		(pin "B52"
		)
		(pin "D2"
		)
		(pin "D10"
		)
		(pin "J9"
		)
		(pin "C31"
		)
		(pin "C30"
		)
		(pin "B21"
		)
		(pin "H9"
		)
		(pin "L14"
		)
		(pin "D8"
		)
		(pin "K48"
		)
		(pin "E46"
		)
		(pin "H10"
		)
		(pin "L18"
		)
		(pin "K17"
		)
		(pin "K16"
		)
		(pin "L32"
		)
		(pin "G19"
		)
		(pin "C59"
		)
		(pin "C60"
		)
		(pin "A8"
		)
		(pin "K49"
		)
		(pin "B60"
		)
		(pin "A60"
		)
		(pin "D58"
		)
		(pin "G61"
		)
		(pin "K46"
		)
		(pin "K47"
		)
		(pin "K55"
		)
		(pin "J64"
		)
		(pin "E17"
		)
		(pin "H3"
		)
		(pin "A3"
		)
		(pin "J25"
		)
		(pin "J49"
		)
		(pin "K63"
		)
		(pin "J2"
		)
		(pin "D49"
		)
		(pin "D48"
		)
		(pin "K8"
		)
		(pin "A19"
		)
		(pin "E19"
		)
		(pin "A32"
		)
		(pin "C58"
		)
		(pin "C56"
		)
		(pin "H62"
		)
		(pin "K60"
		)
		(pin "C27"
		)
		(pin "C26"
		)
		(pin "G45"
		)
		(pin "F48"
		)
		(pin "F49"
		)
		(pin "J26"
		)
		(pin "J27"
		)
		(pin "C15"
		)
		(pin "C14"
		)
		(pin "B49"
		)
		(pin "B9"
		)
		(pin "J10"
		)
		(pin "C53"
		)
		(pin "K10"
		)
		(pin "H49"
		)
		(pin "H48"
		)
		(pin "D16"
		)
		(pin "D17"
		)
		(pin "G49"
		)
		(pin "K14"
		)
		(pin "E2"
		)
		(pin "K34"
		)
		(pin "F28"
		)
		(pin "F29"
		)
		(pin "G11"
		)
		(pin "G10"
		)
		(pin "J8"
		)
		(pin "J53"
		)
		(pin "K5"
		)
		(pin "F51"
		)
		(pin "A55"
		)
		(pin "K19"
		)
		(pin "B53"
		)
		(pin "B12"
		)
		(pin "J47"
		)
		(pin "J48"
		)
		(pin "K56"
		)
		(pin "C54"
		)
		(pin "D54"
		)
		(pin "J51"
		)
		(pin "K59"
		)
		(pin "J59"
		)
		(pin "A7"
		)
		(pin "E61"
		)
		(pin "D62"
		)
		(pin "F60"
		)
		(pin "H16"
		)
		(pin "G18"
		)
		(pin "H17"
		)
		(pin "A59"
		)
		(pin "B62"
		)
		(pin "C61"
		)
		(pin "A62"
		)
		(pin "J39"
		)
		(pin "D36"
		)
		(pin "B48"
		)
		(pin "K9"
		)
		(pin "E31"
		)
		(pin "E30"
		)
		(pin "F8"
		)
		(pin "A4"
		)
		(pin "D6"
		)
		(pin "B6"
		)
		(pin "F65"
		)
		(pin "J17"
		)
		(pin "G2"
		)
		(pin "G64"
		)
		(pin "F64"
		)
		(pin "J13"
		)
		(pin "H1"
		)
		(pin "A5"
		)
		(pin "E8"
		)
		(pin "E34"
		)
		(pin "F37"
		)
		(pin "C6"
		)
		(pin "L28"
		)
		(pin "D7"
		)
		(pin "H26"
		)
		(pin "K44"
		)
		(pin "K43"
		)
		(pin "H46"
		)
		(pin "K15"
		)
		(pin "K50"
		)
		(pin "G53"
		)
		(pin "K26"
		)
		(pin "G37"
		)
		(pin "L11"
		)
		(pin "J20"
		)
		(pin "D53"
		)
		(pin "C41"
		)
		(pin "F46"
		)
		(pin "F45"
		)
		(pin "D35"
		)
		(pin "B61"
		)
		(pin "H61"
		)
		(pin "L51"
		)
		(pin "H54"
		)
		(pin "E18"
		)
		(pin "C19"
		)
		(pin "D45"
		)
		(pin "J44"
		)
		(pin "J45"
		)
		(pin "A36"
		)
		(pin "B38"
		)
		(pin "H36"
		)
		(pin "H37"
		)
		(pin "F58"
		)
		(pin "D59"
		)
		(pin "L55"
		)
		(pin "L34"
		)
		(pin "G57"
		)
		(pin "G51"
		)
		(pin "G50"
		)
		(pin "F30"
		)
		(pin "J24"
		)
		(pin "J16"
		)
		(pin "F57"
		)
		(pin "G31"
		)
		(pin "G30"
		)
		(pin "A44"
		)
		(pin "A45"
		)
		(pin "C47"
		)
		(pin "A6"
		)
		(pin "H31"
		)
		(pin "G36"
		)
		(pin "E20"
		)
		(pin "L24"
		)
		(pin "L13"
		)
		(pin "L52"
		)
		(pin "H38"
		)
		(pin "D47"
		)
		(pin "B33"
		)
		(pin "F36"
		)
		(pin "E35"
		)
		(pin "G39"
		)
		(pin "G38"
		)
		(pin "F54"
		)
		(pin "G55"
		)
		(pin "A40"
		)
		(pin "L53"
		)
		(pin "K35"
		)
		(pin "H56"
		)
		(pin "L37"
		)
		(pin "H59"
		)
		(pin "G60"
		)
		(pin "J4"
		)
		(pin "B59"
		)
		(pin "A10"
		)
		(pin "A11"
		)
		(pin "L50"
		)
		(pin "L49"
		)
		(pin "L9"
		)
		(pin "A51"
		)
		(pin "A50"
		)
		(pin "E63"
		)
		(pin "J1"
		)
		(pin "L19"
		)
		(pin "B36"
		)
		(pin "E48"
		)
		(pin "C44"
		)
		(pin "C45"
		)
		(pin "A41"
		)
		(pin "A42"
		)
		(pin "C42"
		)
		(pin "A52"
		)
		(pin "K61"
		)
		(pin "F53"
		)
		(pin "G48"
		)
		(pin "G47"
		)
		(pin "E47"
		)
		(pin "A12"
		)
		(pin "H35"
		)
		(pin "L61"
		)
		(pin "C34"
		)
		(pin "D51"
		)
		(pin "D52"
		)
		(pin "G23"
		)
		(pin "G22"
		)
		(pin "L57"
		)
		(pin "L44"
		)
		(pin "G52"
		)
		(pin "L8"
		)
		(pin "J61"
		)
		(pin "L41"
		)
		(pin "D4"
		)
		(pin "K38"
		)
		(pin "G65"
		)
		(pin "G8"
		)
		(pin "C8"
		)
		(pin "D56"
		)
		(pin "G56"
		)
		(pin "E51"
		)
		(pin "E50"
		)
		(pin "D38"
		)
		(pin "E45"
		)
		(pin "E44"
		)
		(pin "G44"
		)
		(pin "D28"
		)
		(pin "D29"
		)
		(pin "D24"
		)
		(pin "D25"
		)
		(pin "L62"
		)
		(pin "F61"
		)
		(pin "H20"
		)
		(pin "H21"
		)
		(pin "G9"
		)
		(pin "H51"
		)
		(pin "J52"
		)
		(pin "B40"
		)
		(pin "K36"
		)
		(pin "J38"
		)
		(pin "D65"
		)
		(pin "H47"
		)
		(pin "K21"
		)
		(pin "K20"
		)
		(pin "E42"
		)
		(pin "E41"
		)
		(pin "F43"
		)
		(pin "F42"
		)
		(pin "E39"
		)
		(pin "E38"
		)
		(pin "L36"
		)
		(pin "J29"
		)
		(pin "L12"
		)
		(pin "G5"
		)
		(pin "G54"
		)
		(pin "C18"
		)
		(pin "B37"
		)
		(pin "E11"
		)
		(pin "A37"
		)
		(instances
			(project "jetson-agx-thor-baseboard"
				(path ""
					(reference "J1")
					(unit 11)
				)
			)
		)
	)
	(symbol
		(lib_id "antmicroResistors0402:R_2k2_0402")
		(at 72.39 101.6 270)
		(unit 1)
		(exclude_from_sim no)
		(in_bom no)
		(on_board yes)
		(dnp yes)
		(fields_autoplaced yes)
		(property "Reference" "R354"
			(at 74.93 102.87 90)
			(effects
				(font
					(size 1.27 1.27)
					(thickness 0.15)
				)
				(justify left)
			)
		)
		(property "Value" "R_2k2_0402"
			(at 59.69 121.92 0)
			(effects
				(font
					(size 1.27 1.27)
					(thickness 0.15)
				)
				(justify left bottom)
				(hide yes)
			)
		)
		(property "Footprint" "antmicro-footprints:R_0402_1005Metric"
			(at 57.15 121.92 0)
			(effects
				(font
					(size 1.27 1.27)
					(thickness 0.15)
				)
				(justify left bottom)
				(hide yes)
			)
		)
		(property "Datasheet" "https://www.bourns.com/docs/product-datasheets/cr.pdf"
			(at 54.61 121.92 0)
			(effects
				(font
					(size 1.27 1.27)
					(thickness 0.15)
				)
				(justify left bottom)
				(hide yes)
			)
		)
		(property "Description" "SMD Chip Resistor, 2.2 kohm, ± 1%, 62.5 mW, 0402 [1005 Metric], Thick Film, General Purpose"
			(at 41.91 121.92 0)
			(effects
				(font
					(size 1.27 1.27)
				)
				(justify left bottom)
				(hide yes)
			)
		)
		(property "MPN" "CR0402-FX-2201GLF"
			(at 52.07 121.92 0)
			(effects
				(font
					(size 1.27 1.27)
					(thickness 0.15)
				)
				(justify left bottom)
				(hide yes)
			)
		)
		(property "Manufacturer" "Bourns"
			(at 49.53 121.92 0)
			(effects
				(font
					(size 1.27 1.27)
					(thickness 0.15)
				)
				(justify left bottom)
				(hide yes)
			)
		)
		(property "License" "Apache-2.0"
			(at 46.99 121.92 0)
			(effects
				(font
					(size 1.27 1.27)
					(thickness 0.15)
				)
				(justify left bottom)
				(hide yes)
			)
		)
		(property "Author" "Antmicro"
			(at 44.45 121.92 0)
			(effects
				(font
					(size 1.27 1.27)
					(thickness 0.15)
				)
				(justify left bottom)
				(hide yes)
			)
		)
		(property "Val" "2k2"
			(at 74.93 105.41 90)
			(effects
				(font
					(size 1.27 1.27)
					(thickness 0.15)
				)
				(justify left)
			)
		)
		(property "Tolerance" "1%"
			(at 62.23 121.92 0)
			(effects
				(font
					(size 1.27 1.27)
				)
				(justify left bottom)
				(hide yes)
			)
		)
		(pin "2"
		)
		(pin "1"
		)
		(instances
			(project "jetson-agx-thor-baseboard"
				(path ""
					(reference "R354")
					(unit 1)
				)
			)
		)
	)
	(symbol
		(lib_id "antmicroResistors0402:R_2k2_0402")
		(at 41.91 50.8 270)
		(unit 1)
		(exclude_from_sim no)
		(in_bom no)
		(on_board yes)
		(dnp yes)
		(fields_autoplaced yes)
		(property "Reference" "R356"
			(at 44.45 52.07 90)
			(effects
				(font
					(size 1.27 1.27)
					(thickness 0.15)
				)
				(justify left)
			)
		)
		(property "Value" "R_2k2_0402"
			(at 29.21 71.12 0)
			(effects
				(font
					(size 1.27 1.27)
					(thickness 0.15)
				)
				(justify left bottom)
				(hide yes)
			)
		)
		(property "Footprint" "antmicro-footprints:R_0402_1005Metric"
			(at 26.67 71.12 0)
			(effects
				(font
					(size 1.27 1.27)
					(thickness 0.15)
				)
				(justify left bottom)
				(hide yes)
			)
		)
		(property "Datasheet" "https://www.bourns.com/docs/product-datasheets/cr.pdf"
			(at 24.13 71.12 0)
			(effects
				(font
					(size 1.27 1.27)
					(thickness 0.15)
				)
				(justify left bottom)
				(hide yes)
			)
		)
		(property "Description" "SMD Chip Resistor, 2.2 kohm, ± 1%, 62.5 mW, 0402 [1005 Metric], Thick Film, General Purpose"
			(at 11.43 71.12 0)
			(effects
				(font
					(size 1.27 1.27)
				)
				(justify left bottom)
				(hide yes)
			)
		)
		(property "MPN" "CR0402-FX-2201GLF"
			(at 21.59 71.12 0)
			(effects
				(font
					(size 1.27 1.27)
					(thickness 0.15)
				)
				(justify left bottom)
				(hide yes)
			)
		)
		(property "Manufacturer" "Bourns"
			(at 19.05 71.12 0)
			(effects
				(font
					(size 1.27 1.27)
					(thickness 0.15)
				)
				(justify left bottom)
				(hide yes)
			)
		)
		(property "License" "Apache-2.0"
			(at 16.51 71.12 0)
			(effects
				(font
					(size 1.27 1.27)
					(thickness 0.15)
				)
				(justify left bottom)
				(hide yes)
			)
		)
		(property "Author" "Antmicro"
			(at 13.97 71.12 0)
			(effects
				(font
					(size 1.27 1.27)
					(thickness 0.15)
				)
				(justify left bottom)
				(hide yes)
			)
		)
		(property "Val" "2k2"
			(at 44.45 54.61 90)
			(effects
				(font
					(size 1.27 1.27)
					(thickness 0.15)
				)
				(justify left)
			)
		)
		(property "Tolerance" "1%"
			(at 31.75 71.12 0)
			(effects
				(font
					(size 1.27 1.27)
				)
				(justify left bottom)
				(hide yes)
			)
		)
		(pin "2"
		)
		(pin "1"
		)
		(instances
			(project "jetson-agx-thor-baseboard"
				(path ""
					(reference "R356")
					(unit 1)
				)
			)
		)
	)
	(symbol
		(lib_id "antmicropower:GND")
		(at 83.82 250.19 0)
		(unit 1)
		(exclude_from_sim no)
		(in_bom yes)
		(on_board yes)
		(dnp no)
		(property "Reference" "#PWR021"
			(at 83.82 256.54 0)
			(effects
				(font
					(size 1.27 1.27)
				)
				(justify left bottom)
				(hide yes)
			)
		)
		(property "Value" "GND"
			(at 83.82 254 0)
			(effects
				(font
					(size 1.27 1.27)
					(thickness 0.15)
				)
			)
		)
		(property "Footprint" ""
			(at 92.71 257.81 0)
			(effects
				(font
					(size 1.27 1.27)
					(thickness 0.15)
				)
				(justify left bottom)
				(hide yes)
			)
		)
		(property "Datasheet" ""
			(at 92.71 262.89 0)
			(effects
				(font
					(size 1.27 1.27)
					(thickness 0.15)
				)
				(justify left bottom)
				(hide yes)
			)
		)
		(property "Description" ""
			(at 83.82 250.19 0)
			(effects
				(font
					(size 1.27 1.27)
				)
				(hide yes)
			)
		)
		(property "Author" "Antmicro"
			(at 92.71 257.81 0)
			(effects
				(font
					(size 1.27 1.27)
					(thickness 0.15)
				)
				(justify left bottom)
				(hide yes)
			)
		)
		(property "License" "Apache-2.0"
			(at 92.71 260.35 0)
			(effects
				(font
					(size 1.27 1.27)
					(thickness 0.15)
				)
				(justify left bottom)
				(hide yes)
			)
		)
		(pin "1"
		)
		(instances
			(project "jetson-agx-thor-baseboard"
				(path ""
					(reference "#PWR021")
					(unit 1)
				)
			)
		)
	)
	(symbol
		(lib_id "antmicropower:GND")
		(at 77.47 147.32 0)
		(unit 1)
		(exclude_from_sim no)
		(in_bom yes)
		(on_board yes)
		(dnp no)
		(property "Reference" "#PWR0707"
			(at 77.47 153.67 0)
			(effects
				(font
					(size 1.27 1.27)
				)
				(justify left bottom)
				(hide yes)
			)
		)
		(property "Value" "GND"
			(at 77.47 151.13 0)
			(effects
				(font
					(size 1.27 1.27)
					(thickness 0.15)
				)
			)
		)
		(property "Footprint" ""
			(at 86.36 154.94 0)
			(effects
				(font
					(size 1.27 1.27)
					(thickness 0.15)
				)
				(justify left bottom)
				(hide yes)
			)
		)
		(property "Datasheet" ""
			(at 86.36 160.02 0)
			(effects
				(font
					(size 1.27 1.27)
					(thickness 0.15)
				)
				(justify left bottom)
				(hide yes)
			)
		)
		(property "Description" ""
			(at 77.47 147.32 0)
			(effects
				(font
					(size 1.27 1.27)
				)
				(hide yes)
			)
		)
		(property "Author" "Antmicro"
			(at 86.36 154.94 0)
			(effects
				(font
					(size 1.27 1.27)
					(thickness 0.15)
				)
				(justify left bottom)
				(hide yes)
			)
		)
		(property "License" "Apache-2.0"
			(at 86.36 157.48 0)
			(effects
				(font
					(size 1.27 1.27)
					(thickness 0.15)
				)
				(justify left bottom)
				(hide yes)
			)
		)
		(pin "1"
		)
		(instances
			(project "jetson-agx-thor-baseboard"
				(path ""
					(reference "#PWR0707")
					(unit 1)
				)
			)
		)
	)
	(symbol
		(lib_id "antmicropower:GND")
		(at 106.68 121.92 0)
		(unit 1)
		(exclude_from_sim no)
		(in_bom yes)
		(on_board yes)
		(dnp no)
		(property "Reference" "#PWR010"
			(at 106.68 128.27 0)
			(effects
				(font
					(size 1.27 1.27)
				)
				(justify left bottom)
				(hide yes)
			)
		)
		(property "Value" "GND"
			(at 106.68 125.73 0)
			(effects
				(font
					(size 1.27 1.27)
					(thickness 0.15)
				)
			)
		)
		(property "Footprint" ""
			(at 115.57 129.54 0)
			(effects
				(font
					(size 1.27 1.27)
					(thickness 0.15)
				)
				(justify left bottom)
				(hide yes)
			)
		)
		(property "Datasheet" ""
			(at 115.57 134.62 0)
			(effects
				(font
					(size 1.27 1.27)
					(thickness 0.15)
				)
				(justify left bottom)
				(hide yes)
			)
		)
		(property "Description" ""
			(at 106.68 121.92 0)
			(effects
				(font
					(size 1.27 1.27)
				)
				(hide yes)
			)
		)
		(property "Author" "Antmicro"
			(at 115.57 129.54 0)
			(effects
				(font
					(size 1.27 1.27)
					(thickness 0.15)
				)
				(justify left bottom)
				(hide yes)
			)
		)
		(property "License" "Apache-2.0"
			(at 115.57 132.08 0)
			(effects
				(font
					(size 1.27 1.27)
					(thickness 0.15)
				)
				(justify left bottom)
				(hide yes)
			)
		)
		(pin "1"
		)
		(instances
			(project "jetson-agx-thor-baseboard"
				(path ""
					(reference "#PWR010")
					(unit 1)
				)
			)
		)
	)
	(symbol
		(lib_id "antmicroTestPoints:TP_0.75mm_SMD")
		(at 307.34 214.63 0)
		(mirror y)
		(unit 1)
		(exclude_from_sim no)
		(in_bom no)
		(on_board yes)
		(dnp no)
		(property "Reference" "TP100"
			(at 303.022 214.63 0)
			(effects
				(font
					(size 1.27 1.27)
				)
				(justify left)
			)
		)
		(property "Value" "TP_0.75mm_SMD"
			(at 297.18 218.44 0)
			(effects
				(font
					(size 1.27 1.27)
					(thickness 0.15)
				)
				(justify left bottom)
				(hide yes)
			)
		)
		(property "Footprint" "antmicro-footprints:TP_SMD_0.75mm"
			(at 297.18 220.98 0)
			(effects
				(font
					(size 1.27 1.27)
					(thickness 0.15)
				)
				(justify left bottom)
				(hide yes)
			)
		)
		(property "Datasheet" ""
			(at 289.56 227.33 0)
			(effects
				(font
					(size 1.27 1.27)
					(thickness 0.15)
				)
				(justify left bottom)
				(hide yes)
			)
		)
		(property "Description" "SMT test point"
			(at 307.34 214.63 0)
			(effects
				(font
					(size 1.27 1.27)
				)
				(hide yes)
			)
		)
		(property "MPN" ""
			(at 296.545 226.06 0)
			(effects
				(font
					(size 1.27 1.27)
					(thickness 0.15)
				)
				(justify left bottom)
				(hide yes)
			)
		)
		(property "Manufacturer" ""
			(at 296.545 220.98 0)
			(effects
				(font
					(size 1.27 1.27)
					(thickness 0.15)
				)
				(justify left bottom)
				(hide yes)
			)
		)
		(property "Author" "Antmicro"
			(at 297.18 223.52 0)
			(effects
				(font
					(size 1.27 1.27)
					(thickness 0.15)
				)
				(justify left bottom)
				(hide yes)
			)
		)
		(property "License" "Apache-2.0"
			(at 297.18 226.06 0)
			(effects
				(font
					(size 1.27 1.27)
					(thickness 0.15)
				)
				(justify left bottom)
				(hide yes)
			)
		)
		(pin "1"
		)
		(instances
			(project "jetson-agx-thor-baseboard"
				(path ""
					(reference "TP100")
					(unit 1)
				)
			)
		)
	)
	(symbol
		(lib_id "antmicropower:+1V8")
		(at 57.15 95.25 0)
		(unit 1)
		(exclude_from_sim no)
		(in_bom yes)
		(on_board yes)
		(dnp no)
		(property "Reference" "#PWR022"
			(at 57.15 99.06 0)
			(effects
				(font
					(size 1.27 1.27)
				)
				(justify left bottom)
				(hide yes)
			)
		)
		(property "Value" "+1V8"
			(at 53.975 91.44 0)
			(effects
				(font
					(size 1.27 1.27)
					(thickness 0.15)
				)
				(justify left)
			)
		)
		(property "Footprint" ""
			(at 72.39 102.87 0)
			(effects
				(font
					(size 1.27 1.27)
					(thickness 0.15)
				)
				(justify left bottom)
				(hide yes)
			)
		)
		(property "Datasheet" ""
			(at 72.39 105.41 0)
			(effects
				(font
					(size 1.27 1.27)
					(thickness 0.15)
				)
				(justify left bottom)
				(hide yes)
			)
		)
		(property "Description" ""
			(at 57.15 95.25 0)
			(effects
				(font
					(size 1.27 1.27)
				)
				(hide yes)
			)
		)
		(property "Author" "Antmicro"
			(at 72.39 100.33 0)
			(effects
				(font
					(size 1.27 1.27)
					(thickness 0.15)
				)
				(justify left bottom)
				(hide yes)
			)
		)
		(property "License" "Apache-2.0"
			(at 72.39 102.87 0)
			(effects
				(font
					(size 1.27 1.27)
					(thickness 0.15)
				)
				(justify left bottom)
				(hide yes)
			)
		)
		(pin "1"
		)
		(instances
			(project "jetson-agx-thor-baseboard"
				(path ""
					(reference "#PWR022")
					(unit 1)
				)
			)
		)
	)
	(symbol
		(lib_id "antmicroTestPoints:TP_0.75mm_SMD")
		(at 373.38 63.5 0)
		(unit 1)
		(exclude_from_sim no)
		(in_bom no)
		(on_board yes)
		(dnp no)
		(property "Reference" "TP106"
			(at 377.698 63.5 0)
			(effects
				(font
					(size 1.27 1.27)
				)
				(justify left)
			)
		)
		(property "Value" "TP_0.75mm_SMD"
			(at 383.54 67.31 0)
			(effects
				(font
					(size 1.27 1.27)
					(thickness 0.15)
				)
				(justify left bottom)
				(hide yes)
			)
		)
		(property "Footprint" "antmicro-footprints:TP_SMD_0.75mm"
			(at 383.54 69.85 0)
			(effects
				(font
					(size 1.27 1.27)
					(thickness 0.15)
				)
				(justify left bottom)
				(hide yes)
			)
		)
		(property "Datasheet" ""
			(at 391.16 76.2 0)
			(effects
				(font
					(size 1.27 1.27)
					(thickness 0.15)
				)
				(justify left bottom)
				(hide yes)
			)
		)
		(property "Description" "SMT test point"
			(at 373.38 63.5 0)
			(effects
				(font
					(size 1.27 1.27)
				)
				(hide yes)
			)
		)
		(property "MPN" ""
			(at 384.175 74.93 0)
			(effects
				(font
					(size 1.27 1.27)
					(thickness 0.15)
				)
				(justify left bottom)
				(hide yes)
			)
		)
		(property "Manufacturer" ""
			(at 384.175 69.85 0)
			(effects
				(font
					(size 1.27 1.27)
					(thickness 0.15)
				)
				(justify left bottom)
				(hide yes)
			)
		)
		(property "Author" "Antmicro"
			(at 383.54 72.39 0)
			(effects
				(font
					(size 1.27 1.27)
					(thickness 0.15)
				)
				(justify left bottom)
				(hide yes)
			)
		)
		(property "License" "Apache-2.0"
			(at 383.54 74.93 0)
			(effects
				(font
					(size 1.27 1.27)
					(thickness 0.15)
				)
				(justify left bottom)
				(hide yes)
			)
		)
		(pin "1"
		)
		(instances
			(project "jetson-agx-thor-baseboard"
				(path ""
					(reference "TP106")
					(unit 1)
				)
			)
		)
	)
	(symbol
		(lib_id "antmicropower:GND")
		(at 106.68 250.19 0)
		(unit 1)
		(exclude_from_sim no)
		(in_bom yes)
		(on_board yes)
		(dnp no)
		(property "Reference" "#PWR0699"
			(at 106.68 256.54 0)
			(effects
				(font
					(size 1.27 1.27)
				)
				(justify left bottom)
				(hide yes)
			)
		)
		(property "Value" "GND"
			(at 106.68 254 0)
			(effects
				(font
					(size 1.27 1.27)
					(thickness 0.15)
				)
			)
		)
		(property "Footprint" ""
			(at 115.57 257.81 0)
			(effects
				(font
					(size 1.27 1.27)
					(thickness 0.15)
				)
				(justify left bottom)
				(hide yes)
			)
		)
		(property "Datasheet" ""
			(at 115.57 262.89 0)
			(effects
				(font
					(size 1.27 1.27)
					(thickness 0.15)
				)
				(justify left bottom)
				(hide yes)
			)
		)
		(property "Description" ""
			(at 106.68 250.19 0)
			(effects
				(font
					(size 1.27 1.27)
				)
				(hide yes)
			)
		)
		(property "Author" "Antmicro"
			(at 115.57 257.81 0)
			(effects
				(font
					(size 1.27 1.27)
					(thickness 0.15)
				)
				(justify left bottom)
				(hide yes)
			)
		)
		(property "License" "Apache-2.0"
			(at 115.57 260.35 0)
			(effects
				(font
					(size 1.27 1.27)
					(thickness 0.15)
				)
				(justify left bottom)
				(hide yes)
			)
		)
		(pin "1"
		)
		(instances
			(project "jetson-agx-thor-baseboard"
				(path ""
					(reference "#PWR0699")
					(unit 1)
				)
			)
		)
	)
	(symbol
		(lib_id "antmicroResistors0402:R_2k2_0402")
		(at 146.05 100.33 270)
		(unit 1)
		(exclude_from_sim no)
		(in_bom yes)
		(on_board yes)
		(dnp no)
		(fields_autoplaced yes)
		(property "Reference" "R377"
			(at 148.59 101.6 90)
			(effects
				(font
					(size 1.27 1.27)
					(thickness 0.15)
				)
				(justify left)
			)
		)
		(property "Value" "R_2k2_0402"
			(at 133.35 120.65 0)
			(effects
				(font
					(size 1.27 1.27)
					(thickness 0.15)
				)
				(justify left bottom)
				(hide yes)
			)
		)
		(property "Footprint" "antmicro-footprints:R_0402_1005Metric"
			(at 130.81 120.65 0)
			(effects
				(font
					(size 1.27 1.27)
					(thickness 0.15)
				)
				(justify left bottom)
				(hide yes)
			)
		)
		(property "Datasheet" "https://www.bourns.com/docs/product-datasheets/cr.pdf"
			(at 128.27 120.65 0)
			(effects
				(font
					(size 1.27 1.27)
					(thickness 0.15)
				)
				(justify left bottom)
				(hide yes)
			)
		)
		(property "Description" "SMD Chip Resistor, 2.2 kohm, ± 1%, 62.5 mW, 0402 [1005 Metric], Thick Film, General Purpose"
			(at 115.57 120.65 0)
			(effects
				(font
					(size 1.27 1.27)
				)
				(justify left bottom)
				(hide yes)
			)
		)
		(property "MPN" "CR0402-FX-2201GLF"
			(at 125.73 120.65 0)
			(effects
				(font
					(size 1.27 1.27)
					(thickness 0.15)
				)
				(justify left bottom)
				(hide yes)
			)
		)
		(property "Manufacturer" "Bourns"
			(at 123.19 120.65 0)
			(effects
				(font
					(size 1.27 1.27)
					(thickness 0.15)
				)
				(justify left bottom)
				(hide yes)
			)
		)
		(property "License" "Apache-2.0"
			(at 120.65 120.65 0)
			(effects
				(font
					(size 1.27 1.27)
					(thickness 0.15)
				)
				(justify left bottom)
				(hide yes)
			)
		)
		(property "Author" "Antmicro"
			(at 118.11 120.65 0)
			(effects
				(font
					(size 1.27 1.27)
					(thickness 0.15)
				)
				(justify left bottom)
				(hide yes)
			)
		)
		(property "Val" "2k2"
			(at 148.59 104.14 90)
			(effects
				(font
					(size 1.27 1.27)
					(thickness 0.15)
				)
				(justify left)
			)
		)
		(property "Tolerance" "1%"
			(at 135.89 120.65 0)
			(effects
				(font
					(size 1.27 1.27)
				)
				(justify left bottom)
				(hide yes)
			)
		)
		(pin "2"
		)
		(pin "1"
		)
		(instances
			(project "jetson-agx-thor-baseboard"
				(path ""
					(reference "R377")
					(unit 1)
				)
			)
		)
	)
	(symbol
		(lib_id "antmicroResistors0402:R_2k2_0402")
		(at 62.23 101.6 270)
		(unit 1)
		(exclude_from_sim no)
		(in_bom no)
		(on_board yes)
		(dnp yes)
		(fields_autoplaced yes)
		(property "Reference" "R353"
			(at 64.77 102.87 90)
			(effects
				(font
					(size 1.27 1.27)
					(thickness 0.15)
				)
				(justify left)
			)
		)
		(property "Value" "R_2k2_0402"
			(at 49.53 121.92 0)
			(effects
				(font
					(size 1.27 1.27)
					(thickness 0.15)
				)
				(justify left bottom)
				(hide yes)
			)
		)
		(property "Footprint" "antmicro-footprints:R_0402_1005Metric"
			(at 46.99 121.92 0)
			(effects
				(font
					(size 1.27 1.27)
					(thickness 0.15)
				)
				(justify left bottom)
				(hide yes)
			)
		)
		(property "Datasheet" "https://www.bourns.com/docs/product-datasheets/cr.pdf"
			(at 44.45 121.92 0)
			(effects
				(font
					(size 1.27 1.27)
					(thickness 0.15)
				)
				(justify left bottom)
				(hide yes)
			)
		)
		(property "Description" "SMD Chip Resistor, 2.2 kohm, ± 1%, 62.5 mW, 0402 [1005 Metric], Thick Film, General Purpose"
			(at 31.75 121.92 0)
			(effects
				(font
					(size 1.27 1.27)
				)
				(justify left bottom)
				(hide yes)
			)
		)
		(property "MPN" "CR0402-FX-2201GLF"
			(at 41.91 121.92 0)
			(effects
				(font
					(size 1.27 1.27)
					(thickness 0.15)
				)
				(justify left bottom)
				(hide yes)
			)
		)
		(property "Manufacturer" "Bourns"
			(at 39.37 121.92 0)
			(effects
				(font
					(size 1.27 1.27)
					(thickness 0.15)
				)
				(justify left bottom)
				(hide yes)
			)
		)
		(property "License" "Apache-2.0"
			(at 36.83 121.92 0)
			(effects
				(font
					(size 1.27 1.27)
					(thickness 0.15)
				)
				(justify left bottom)
				(hide yes)
			)
		)
		(property "Author" "Antmicro"
			(at 34.29 121.92 0)
			(effects
				(font
					(size 1.27 1.27)
					(thickness 0.15)
				)
				(justify left bottom)
				(hide yes)
			)
		)
		(property "Val" "2k2"
			(at 64.77 105.41 90)
			(effects
				(font
					(size 1.27 1.27)
					(thickness 0.15)
				)
				(justify left)
			)
		)
		(property "Tolerance" "1%"
			(at 52.07 121.92 0)
			(effects
				(font
					(size 1.27 1.27)
				)
				(justify left bottom)
				(hide yes)
			)
		)
		(pin "2"
		)
		(pin "1"
		)
		(instances
			(project "jetson-agx-thor-baseboard"
				(path ""
					(reference "R353")
					(unit 1)
				)
			)
		)
	)
	(symbol
		(lib_id "antmicroResistors0402:R_2k2_0402")
		(at 62.23 50.8 270)
		(unit 1)
		(exclude_from_sim no)
		(in_bom no)
		(on_board yes)
		(dnp yes)
		(fields_autoplaced yes)
		(property "Reference" "R358"
			(at 64.77 52.07 90)
			(effects
				(font
					(size 1.27 1.27)
					(thickness 0.15)
				)
				(justify left)
			)
		)
		(property "Value" "R_2k2_0402"
			(at 49.53 71.12 0)
			(effects
				(font
					(size 1.27 1.27)
					(thickness 0.15)
				)
				(justify left bottom)
				(hide yes)
			)
		)
		(property "Footprint" "antmicro-footprints:R_0402_1005Metric"
			(at 46.99 71.12 0)
			(effects
				(font
					(size 1.27 1.27)
					(thickness 0.15)
				)
				(justify left bottom)
				(hide yes)
			)
		)
		(property "Datasheet" "https://www.bourns.com/docs/product-datasheets/cr.pdf"
			(at 44.45 71.12 0)
			(effects
				(font
					(size 1.27 1.27)
					(thickness 0.15)
				)
				(justify left bottom)
				(hide yes)
			)
		)
		(property "Description" "SMD Chip Resistor, 2.2 kohm, ± 1%, 62.5 mW, 0402 [1005 Metric], Thick Film, General Purpose"
			(at 31.75 71.12 0)
			(effects
				(font
					(size 1.27 1.27)
				)
				(justify left bottom)
				(hide yes)
			)
		)
		(property "MPN" "CR0402-FX-2201GLF"
			(at 41.91 71.12 0)
			(effects
				(font
					(size 1.27 1.27)
					(thickness 0.15)
				)
				(justify left bottom)
				(hide yes)
			)
		)
		(property "Manufacturer" "Bourns"
			(at 39.37 71.12 0)
			(effects
				(font
					(size 1.27 1.27)
					(thickness 0.15)
				)
				(justify left bottom)
				(hide yes)
			)
		)
		(property "License" "Apache-2.0"
			(at 36.83 71.12 0)
			(effects
				(font
					(size 1.27 1.27)
					(thickness 0.15)
				)
				(justify left bottom)
				(hide yes)
			)
		)
		(property "Author" "Antmicro"
			(at 34.29 71.12 0)
			(effects
				(font
					(size 1.27 1.27)
					(thickness 0.15)
				)
				(justify left bottom)
				(hide yes)
			)
		)
		(property "Val" "2k2"
			(at 64.77 54.61 90)
			(effects
				(font
					(size 1.27 1.27)
					(thickness 0.15)
				)
				(justify left)
			)
		)
		(property "Tolerance" "1%"
			(at 52.07 71.12 0)
			(effects
				(font
					(size 1.27 1.27)
				)
				(justify left bottom)
				(hide yes)
			)
		)
		(pin "2"
		)
		(pin "1"
		)
		(instances
			(project "jetson-agx-thor-baseboard"
				(path ""
					(reference "R358")
					(unit 1)
				)
			)
		)
	)
	(symbol
		(lib_id "antmicropower:GND")
		(at 83.82 186.69 0)
		(unit 1)
		(exclude_from_sim no)
		(in_bom yes)
		(on_board yes)
		(dnp no)
		(property "Reference" "#PWR0721"
			(at 83.82 193.04 0)
			(effects
				(font
					(size 1.27 1.27)
				)
				(justify left bottom)
				(hide yes)
			)
		)
		(property "Value" "GND"
			(at 83.82 190.5 0)
			(effects
				(font
					(size 1.27 1.27)
					(thickness 0.15)
				)
			)
		)
		(property "Footprint" ""
			(at 92.71 194.31 0)
			(effects
				(font
					(size 1.27 1.27)
					(thickness 0.15)
				)
				(justify left bottom)
				(hide yes)
			)
		)
		(property "Datasheet" ""
			(at 92.71 199.39 0)
			(effects
				(font
					(size 1.27 1.27)
					(thickness 0.15)
				)
				(justify left bottom)
				(hide yes)
			)
		)
		(property "Description" ""
			(at 83.82 186.69 0)
			(effects
				(font
					(size 1.27 1.27)
				)
				(hide yes)
			)
		)
		(property "Author" "Antmicro"
			(at 92.71 194.31 0)
			(effects
				(font
					(size 1.27 1.27)
					(thickness 0.15)
				)
				(justify left bottom)
				(hide yes)
			)
		)
		(property "License" "Apache-2.0"
			(at 92.71 196.85 0)
			(effects
				(font
					(size 1.27 1.27)
					(thickness 0.15)
				)
				(justify left bottom)
				(hide yes)
			)
		)
		(pin "1"
		)
		(instances
			(project "jetson-agx-thor-baseboard"
				(path ""
					(reference "#PWR0721")
					(unit 1)
				)
			)
		)
	)
	(symbol
		(lib_id "antmicropower:GND")
		(at 83.82 71.12 0)
		(unit 1)
		(exclude_from_sim no)
		(in_bom yes)
		(on_board yes)
		(dnp no)
		(property "Reference" "#PWR0677"
			(at 83.82 77.47 0)
			(effects
				(font
					(size 1.27 1.27)
				)
				(justify left bottom)
				(hide yes)
			)
		)
		(property "Value" "GND"
			(at 83.82 74.93 0)
			(effects
				(font
					(size 1.27 1.27)
					(thickness 0.15)
				)
			)
		)
		(property "Footprint" ""
			(at 92.71 78.74 0)
			(effects
				(font
					(size 1.27 1.27)
					(thickness 0.15)
				)
				(justify left bottom)
				(hide yes)
			)
		)
		(property "Datasheet" ""
			(at 92.71 83.82 0)
			(effects
				(font
					(size 1.27 1.27)
					(thickness 0.15)
				)
				(justify left bottom)
				(hide yes)
			)
		)
		(property "Description" ""
			(at 83.82 71.12 0)
			(effects
				(font
					(size 1.27 1.27)
				)
				(hide yes)
			)
		)
		(property "Author" "Antmicro"
			(at 92.71 78.74 0)
			(effects
				(font
					(size 1.27 1.27)
					(thickness 0.15)
				)
				(justify left bottom)
				(hide yes)
			)
		)
		(property "License" "Apache-2.0"
			(at 92.71 81.28 0)
			(effects
				(font
					(size 1.27 1.27)
					(thickness 0.15)
				)
				(justify left bottom)
				(hide yes)
			)
		)
		(pin "1"
		)
		(instances
			(project "jetson-agx-thor-baseboard"
				(path ""
					(reference "#PWR0677")
					(unit 1)
				)
			)
		)
	)
	(symbol
		(lib_id "antmicroTestPoints:TP_0.75mm_SMD")
		(at 307.34 212.09 0)
		(mirror y)
		(unit 1)
		(exclude_from_sim no)
		(in_bom no)
		(on_board yes)
		(dnp no)
		(property "Reference" "TP99"
			(at 303.022 212.09 0)
			(effects
				(font
					(size 1.27 1.27)
				)
				(justify left)
			)
		)
		(property "Value" "TP_0.75mm_SMD"
			(at 297.18 215.9 0)
			(effects
				(font
					(size 1.27 1.27)
					(thickness 0.15)
				)
				(justify left bottom)
				(hide yes)
			)
		)
		(property "Footprint" "antmicro-footprints:TP_SMD_0.75mm"
			(at 297.18 218.44 0)
			(effects
				(font
					(size 1.27 1.27)
					(thickness 0.15)
				)
				(justify left bottom)
				(hide yes)
			)
		)
		(property "Datasheet" ""
			(at 289.56 224.79 0)
			(effects
				(font
					(size 1.27 1.27)
					(thickness 0.15)
				)
				(justify left bottom)
				(hide yes)
			)
		)
		(property "Description" "SMT test point"
			(at 307.34 212.09 0)
			(effects
				(font
					(size 1.27 1.27)
				)
				(hide yes)
			)
		)
		(property "MPN" ""
			(at 296.545 223.52 0)
			(effects
				(font
					(size 1.27 1.27)
					(thickness 0.15)
				)
				(justify left bottom)
				(hide yes)
			)
		)
		(property "Manufacturer" ""
			(at 296.545 218.44 0)
			(effects
				(font
					(size 1.27 1.27)
					(thickness 0.15)
				)
				(justify left bottom)
				(hide yes)
			)
		)
		(property "Author" "Antmicro"
			(at 297.18 220.98 0)
			(effects
				(font
					(size 1.27 1.27)
					(thickness 0.15)
				)
				(justify left bottom)
				(hide yes)
			)
		)
		(property "License" "Apache-2.0"
			(at 297.18 223.52 0)
			(effects
				(font
					(size 1.27 1.27)
					(thickness 0.15)
				)
				(justify left bottom)
				(hide yes)
			)
		)
		(pin "1"
		)
		(instances
			(project "jetson-agx-thor-baseboard"
				(path ""
					(reference "TP99")
					(unit 1)
				)
			)
		)
	)
	(symbol
		(lib_id "antmicroTestPoints:TP_0.75mm_SMD")
		(at 304.8 161.29 0)
		(mirror y)
		(unit 1)
		(exclude_from_sim no)
		(in_bom no)
		(on_board yes)
		(dnp no)
		(property "Reference" "TP104"
			(at 300.482 161.29 0)
			(effects
				(font
					(size 1.27 1.27)
				)
				(justify left)
			)
		)
		(property "Value" "TP_0.75mm_SMD"
			(at 294.64 165.1 0)
			(effects
				(font
					(size 1.27 1.27)
					(thickness 0.15)
				)
				(justify left bottom)
				(hide yes)
			)
		)
		(property "Footprint" "antmicro-footprints:TP_SMD_0.75mm"
			(at 294.64 167.64 0)
			(effects
				(font
					(size 1.27 1.27)
					(thickness 0.15)
				)
				(justify left bottom)
				(hide yes)
			)
		)
		(property "Datasheet" ""
			(at 287.02 173.99 0)
			(effects
				(font
					(size 1.27 1.27)
					(thickness 0.15)
				)
				(justify left bottom)
				(hide yes)
			)
		)
		(property "Description" "SMT test point"
			(at 304.8 161.29 0)
			(effects
				(font
					(size 1.27 1.27)
				)
				(hide yes)
			)
		)
		(property "MPN" ""
			(at 294.005 172.72 0)
			(effects
				(font
					(size 1.27 1.27)
					(thickness 0.15)
				)
				(justify left bottom)
				(hide yes)
			)
		)
		(property "Manufacturer" ""
			(at 294.005 167.64 0)
			(effects
				(font
					(size 1.27 1.27)
					(thickness 0.15)
				)
				(justify left bottom)
				(hide yes)
			)
		)
		(property "Author" "Antmicro"
			(at 294.64 170.18 0)
			(effects
				(font
					(size 1.27 1.27)
					(thickness 0.15)
				)
				(justify left bottom)
				(hide yes)
			)
		)
		(property "License" "Apache-2.0"
			(at 294.64 172.72 0)
			(effects
				(font
					(size 1.27 1.27)
					(thickness 0.15)
				)
				(justify left bottom)
				(hide yes)
			)
		)
		(pin "1"
		)
		(instances
			(project "jetson-agx-thor-baseboard"
				(path ""
					(reference "TP104")
					(unit 1)
				)
			)
		)
	)
	(symbol
		(lib_id "antmicroResistors0402:R_2k2_0402")
		(at 72.39 50.8 270)
		(unit 1)
		(exclude_from_sim no)
		(in_bom no)
		(on_board yes)
		(dnp yes)
		(fields_autoplaced yes)
		(property "Reference" "R359"
			(at 74.93 52.07 90)
			(effects
				(font
					(size 1.27 1.27)
					(thickness 0.15)
				)
				(justify left)
			)
		)
		(property "Value" "R_2k2_0402"
			(at 59.69 71.12 0)
			(effects
				(font
					(size 1.27 1.27)
					(thickness 0.15)
				)
				(justify left bottom)
				(hide yes)
			)
		)
		(property "Footprint" "antmicro-footprints:R_0402_1005Metric"
			(at 57.15 71.12 0)
			(effects
				(font
					(size 1.27 1.27)
					(thickness 0.15)
				)
				(justify left bottom)
				(hide yes)
			)
		)
		(property "Datasheet" "https://www.bourns.com/docs/product-datasheets/cr.pdf"
			(at 54.61 71.12 0)
			(effects
				(font
					(size 1.27 1.27)
					(thickness 0.15)
				)
				(justify left bottom)
				(hide yes)
			)
		)
		(property "Description" "SMD Chip Resistor, 2.2 kohm, ± 1%, 62.5 mW, 0402 [1005 Metric], Thick Film, General Purpose"
			(at 41.91 71.12 0)
			(effects
				(font
					(size 1.27 1.27)
				)
				(justify left bottom)
				(hide yes)
			)
		)
		(property "MPN" "CR0402-FX-2201GLF"
			(at 52.07 71.12 0)
			(effects
				(font
					(size 1.27 1.27)
					(thickness 0.15)
				)
				(justify left bottom)
				(hide yes)
			)
		)
		(property "Manufacturer" "Bourns"
			(at 49.53 71.12 0)
			(effects
				(font
					(size 1.27 1.27)
					(thickness 0.15)
				)
				(justify left bottom)
				(hide yes)
			)
		)
		(property "License" "Apache-2.0"
			(at 46.99 71.12 0)
			(effects
				(font
					(size 1.27 1.27)
					(thickness 0.15)
				)
				(justify left bottom)
				(hide yes)
			)
		)
		(property "Author" "Antmicro"
			(at 44.45 71.12 0)
			(effects
				(font
					(size 1.27 1.27)
					(thickness 0.15)
				)
				(justify left bottom)
				(hide yes)
			)
		)
		(property "Val" "2k2"
			(at 74.93 54.61 90)
			(effects
				(font
					(size 1.27 1.27)
					(thickness 0.15)
				)
				(justify left)
			)
		)
		(property "Tolerance" "1%"
			(at 62.23 71.12 0)
			(effects
				(font
					(size 1.27 1.27)
				)
				(justify left bottom)
				(hide yes)
			)
		)
		(pin "2"
		)
		(pin "1"
		)
		(instances
			(project "jetson-agx-thor-baseboard"
				(path ""
					(reference "R359")
					(unit 1)
				)
			)
		)
	)
	(symbol
		(lib_id "antmicropower:+3V3")
		(at 100.33 85.09 0)
		(unit 1)
		(exclude_from_sim no)
		(in_bom yes)
		(on_board yes)
		(dnp no)
		(property "Reference" "#PWR05"
			(at 100.33 88.9 0)
			(effects
				(font
					(size 1.27 1.27)
				)
				(justify left bottom)
				(hide yes)
			)
		)
		(property "Value" "+3V3"
			(at 97.155 81.28 0)
			(effects
				(font
					(size 1.27 1.27)
					(thickness 0.15)
				)
				(justify left)
			)
		)
		(property "Footprint" ""
			(at 115.57 92.71 0)
			(effects
				(font
					(size 1.27 1.27)
					(thickness 0.15)
				)
				(justify left bottom)
				(hide yes)
			)
		)
		(property "Datasheet" ""
			(at 115.57 95.25 0)
			(effects
				(font
					(size 1.27 1.27)
					(thickness 0.15)
				)
				(justify left bottom)
				(hide yes)
			)
		)
		(property "Description" ""
			(at 100.33 85.09 0)
			(effects
				(font
					(size 1.27 1.27)
				)
				(hide yes)
			)
		)
		(property "Author" "Antmicro"
			(at 115.57 87.63 0)
			(effects
				(font
					(size 1.27 1.27)
					(thickness 0.15)
				)
				(justify left bottom)
				(hide yes)
			)
		)
		(property "License" "Apache-2.0"
			(at 115.57 90.17 0)
			(effects
				(font
					(size 1.27 1.27)
					(thickness 0.15)
				)
				(justify left bottom)
				(hide yes)
			)
		)
		(pin "1"
		)
		(instances
			(project "jetson-agx-thor-baseboard"
				(path ""
					(reference "#PWR05")
					(unit 1)
				)
			)
		)
	)
	(symbol
		(lib_id "antmicropower:GND")
		(at 113.03 147.32 0)
		(unit 1)
		(exclude_from_sim no)
		(in_bom yes)
		(on_board yes)
		(dnp no)
		(property "Reference" "#PWR0737"
			(at 113.03 153.67 0)
			(effects
				(font
					(size 1.27 1.27)
				)
				(justify left bottom)
				(hide yes)
			)
		)
		(property "Value" "GND"
			(at 113.03 151.13 0)
			(effects
				(font
					(size 1.27 1.27)
					(thickness 0.15)
				)
			)
		)
		(property "Footprint" ""
			(at 121.92 154.94 0)
			(effects
				(font
					(size 1.27 1.27)
					(thickness 0.15)
				)
				(justify left bottom)
				(hide yes)
			)
		)
		(property "Datasheet" ""
			(at 121.92 160.02 0)
			(effects
				(font
					(size 1.27 1.27)
					(thickness 0.15)
				)
				(justify left bottom)
				(hide yes)
			)
		)
		(property "Description" ""
			(at 113.03 147.32 0)
			(effects
				(font
					(size 1.27 1.27)
				)
				(hide yes)
			)
		)
		(property "Author" "Antmicro"
			(at 121.92 154.94 0)
			(effects
				(font
					(size 1.27 1.27)
					(thickness 0.15)
				)
				(justify left bottom)
				(hide yes)
			)
		)
		(property "License" "Apache-2.0"
			(at 121.92 157.48 0)
			(effects
				(font
					(size 1.27 1.27)
					(thickness 0.15)
				)
				(justify left bottom)
				(hide yes)
			)
		)
		(pin "1"
		)
		(instances
			(project "jetson-agx-thor-baseboard"
				(path ""
					(reference "#PWR0737")
					(unit 1)
				)
			)
		)
	)
	(symbol
		(lib_id "antmicroCapacitors0402:C_100n_0402")
		(at 90.17 91.44 270)
		(mirror x)
		(unit 1)
		(exclude_from_sim no)
		(in_bom yes)
		(on_board yes)
		(dnp no)
		(property "Reference" "C1"
			(at 88.265 87.63 90)
			(effects
				(font
					(size 1.27 1.27)
				)
				(justify right)
			)
		)
		(property "Value" "C_100n_0402"
			(at 80.01 71.12 0)
			(effects
				(font
					(size 1.27 1.27)
					(thickness 0.15)
				)
				(justify left bottom)
				(hide yes)
			)
		)
		(property "Footprint" "antmicro-footprints:C_0402_1005Metric"
			(at 77.47 71.12 0)
			(effects
				(font
					(size 1.27 1.27)
					(thickness 0.15)
				)
				(justify left bottom)
				(hide yes)
			)
		)
		(property "Datasheet" "https://www.murata.com/products/productdetail?partno=GRM155R61H104KE14%23"
			(at 74.93 71.12 0)
			(effects
				(font
					(size 1.27 1.27)
					(thickness 0.15)
				)
				(justify left bottom)
				(hide yes)
			)
		)
		(property "Description" "SMD Multilayer Ceramic Capacitor, 0.1 µF, 50 V, 0402 [1005 Metric], ± 10%, X5R, GRM Series"
			(at 90.17 91.44 0)
			(effects
				(font
					(size 1.27 1.27)
				)
				(hide yes)
			)
		)
		(property "Manufacturer" "Murata"
			(at 69.85 71.12 0)
			(effects
				(font
					(size 1.27 1.27)
					(thickness 0.15)
				)
				(justify left bottom)
				(hide yes)
			)
		)
		(property "MPN" "GRM155R61H104KE14D"
			(at 72.39 71.12 0)
			(effects
				(font
					(size 1.27 1.27)
					(thickness 0.15)
				)
				(justify left bottom)
				(hide yes)
			)
		)
		(property "Val" "100n"
			(at 88.265 90.17 90)
			(effects
				(font
					(size 1.27 1.27)
					(thickness 0.15)
				)
				(justify right)
			)
		)
		(property "License" "Apache-2.0"
			(at 67.31 71.12 0)
			(effects
				(font
					(size 1.27 1.27)
					(thickness 0.15)
				)
				(justify left bottom)
				(hide yes)
			)
		)
		(property "Author" "Antmicro"
			(at 64.77 71.12 0)
			(effects
				(font
					(size 1.27 1.27)
					(thickness 0.15)
				)
				(justify left bottom)
				(hide yes)
			)
		)
		(property "Voltage" "50V"
			(at 62.23 71.12 0)
			(effects
				(font
					(size 1.27 1.27)
				)
				(justify left bottom)
				(hide yes)
			)
		)
		(property "Dielectric" "X5R"
			(at 59.69 71.12 0)
			(effects
				(font
					(size 1.27 1.27)
				)
				(justify left bottom)
				(hide yes)
			)
		)
		(pin "1"
		)
		(pin "2"
		)
		(instances
			(project "jetson-agx-thor-baseboard"
				(path ""
					(reference "C1")
					(unit 1)
				)
			)
		)
	)
	(symbol
		(lib_id "antmicroLogicTranslatorsLevelShifters:SN74AXC8T245_UQFN")
		(at 85.09 149.86 0)
		(unit 1)
		(exclude_from_sim no)
		(in_bom yes)
		(on_board yes)
		(dnp no)
		(fields_autoplaced yes)
		(property "Reference" "U78"
			(at 95.25 142.24 0)
			(effects
				(font
					(size 1.27 1.27)
					(thickness 0.15)
				)
			)
		)
		(property "Value" "SN74AXC8T245_UQFN"
			(at 135.89 154.94 0)
			(effects
				(font
					(size 1.27 1.27)
					(thickness 0.15)
				)
				(justify left bottom)
				(hide yes)
			)
		)
		(property "Footprint" "antmicro-footprints:UQFN-24_2x4mm_P0.4mm_Texas_RJW0024A"
			(at 135.89 160.02 0)
			(effects
				(font
					(size 1.27 1.27)
					(thickness 0.15)
				)
				(justify left bottom)
				(hide yes)
			)
		)
		(property "Datasheet" "https://www.ti.com/lit/ds/symlink/sn74axc8t245.pdf?ts=1702327536011"
			(at 135.89 162.56 0)
			(effects
				(font
					(size 1.27 1.27)
					(thickness 0.15)
				)
				(justify left bottom)
				(hide yes)
			)
		)
		(property "Description" "8-bit dual-supply bus transceiver"
			(at 135.89 170.18 0)
			(effects
				(font
					(size 1.27 1.27)
				)
				(justify left bottom)
				(hide yes)
			)
		)
		(property "MPN" "SN74AXC8T245RJWR"
			(at 95.25 144.78 0)
			(effects
				(font
					(size 1.27 1.27)
				)
			)
		)
		(property "Manufacturer" "Texas Instruments"
			(at 135.89 157.48 0)
			(effects
				(font
					(size 1.27 1.27)
				)
				(justify left bottom)
				(hide yes)
			)
		)
		(property "Author" "Antmicro"
			(at 135.89 165.1 0)
			(effects
				(font
					(size 1.27 1.27)
					(thickness 0.15)
				)
				(justify left bottom)
				(hide yes)
			)
		)
		(property "License" "Apache-2.0"
			(at 135.89 167.64 0)
			(effects
				(font
					(size 1.27 1.27)
					(thickness 0.15)
				)
				(justify left bottom)
				(hide yes)
			)
		)
		(pin "20"
		)
		(pin "8"
		)
		(pin "23"
		)
		(pin "7"
		)
		(pin "13"
		)
		(pin "16"
		)
		(pin "6"
		)
		(pin "11"
		)
		(pin "18"
		)
		(pin "15"
		)
		(pin "17"
		)
		(pin "19"
		)
		(pin "1"
		)
		(pin "14"
		)
		(pin "5"
		)
		(pin "10"
		)
		(pin "2"
		)
		(pin "22"
		)
		(pin "24"
		)
		(pin "3"
		)
		(pin "12"
		)
		(pin "4"
		)
		(pin "9"
		)
		(pin "21"
		)
		(instances
			(project "jetson-agx-thor-baseboard"
				(path ""
					(reference "U78")
					(unit 1)
				)
			)
		)
	)
	(symbol
		(lib_id "antmicropower:+1V8")
		(at 80.01 245.11 0)
		(unit 1)
		(exclude_from_sim no)
		(in_bom yes)
		(on_board yes)
		(dnp no)
		(property "Reference" "#PWR020"
			(at 80.01 248.92 0)
			(effects
				(font
					(size 1.27 1.27)
				)
				(justify left bottom)
				(hide yes)
			)
		)
		(property "Value" "+1V8"
			(at 76.835 241.3 0)
			(effects
				(font
					(size 1.27 1.27)
					(thickness 0.15)
				)
				(justify left)
			)
		)
		(property "Footprint" ""
			(at 95.25 252.73 0)
			(effects
				(font
					(size 1.27 1.27)
					(thickness 0.15)
				)
				(justify left bottom)
				(hide yes)
			)
		)
		(property "Datasheet" ""
			(at 95.25 255.27 0)
			(effects
				(font
					(size 1.27 1.27)
					(thickness 0.15)
				)
				(justify left bottom)
				(hide yes)
			)
		)
		(property "Description" ""
			(at 80.01 245.11 0)
			(effects
				(font
					(size 1.27 1.27)
				)
				(hide yes)
			)
		)
		(property "Author" "Antmicro"
			(at 95.25 250.19 0)
			(effects
				(font
					(size 1.27 1.27)
					(thickness 0.15)
				)
				(justify left bottom)
				(hide yes)
			)
		)
		(property "License" "Apache-2.0"
			(at 95.25 252.73 0)
			(effects
				(font
					(size 1.27 1.27)
					(thickness 0.15)
				)
				(justify left bottom)
				(hide yes)
			)
		)
		(pin "1"
		)
		(instances
			(project "jetson-agx-thor-baseboard"
				(path ""
					(reference "#PWR020")
					(unit 1)
				)
			)
		)
	)
	(symbol
		(lib_id "antmicropower:+3V3")
		(at 130.81 95.25 0)
		(unit 1)
		(exclude_from_sim no)
		(in_bom yes)
		(on_board yes)
		(dnp no)
		(property "Reference" "#PWR025"
			(at 130.81 99.06 0)
			(effects
				(font
					(size 1.27 1.27)
				)
				(justify left bottom)
				(hide yes)
			)
		)
		(property "Value" "+3V3"
			(at 127.635 91.44 0)
			(effects
				(font
					(size 1.27 1.27)
					(thickness 0.15)
				)
				(justify left)
			)
		)
		(property "Footprint" ""
			(at 146.05 102.87 0)
			(effects
				(font
					(size 1.27 1.27)
					(thickness 0.15)
				)
				(justify left bottom)
				(hide yes)
			)
		)
		(property "Datasheet" ""
			(at 146.05 105.41 0)
			(effects
				(font
					(size 1.27 1.27)
					(thickness 0.15)
				)
				(justify left bottom)
				(hide yes)
			)
		)
		(property "Description" ""
			(at 130.81 95.25 0)
			(effects
				(font
					(size 1.27 1.27)
				)
				(hide yes)
			)
		)
		(property "Author" "Antmicro"
			(at 146.05 97.79 0)
			(effects
				(font
					(size 1.27 1.27)
					(thickness 0.15)
				)
				(justify left bottom)
				(hide yes)
			)
		)
		(property "License" "Apache-2.0"
			(at 146.05 100.33 0)
			(effects
				(font
					(size 1.27 1.27)
					(thickness 0.15)
				)
				(justify left bottom)
				(hide yes)
			)
		)
		(pin "1"
		)
		(instances
			(project "jetson-agx-thor-baseboard"
				(path ""
					(reference "#PWR025")
					(unit 1)
				)
			)
		)
	)
	(symbol
		(lib_id "antmicroB2BConnectors:Hermaphroditic_Molex_203456-0003_CUSTOM_Jetson_AGX_Thor_H8mm")
		(at 318.77 34.29 0)
		(unit 9)
		(exclude_from_sim no)
		(in_bom yes)
		(on_board yes)
		(dnp no)
		(fields_autoplaced yes)
		(property "Reference" "J1"
			(at 342.265 26.67 0)
			(effects
				(font
					(size 1.27 1.27)
				)
			)
		)
		(property "Value" "Hermaphroditic_Molex_203456-0003_CUSTOM_Jetson_AGX_Thor_H8mm"
			(at 395.224 40.386 0)
			(effects
				(font
					(size 1.27 1.27)
				)
				(justify left bottom)
				(hide yes)
			)
		)
		(property "Footprint" "antmicro-footprints:Conn_Hermaphroditic_Molex_203456-0003_mirrored"
			(at 395.224 42.672 0)
			(effects
				(font
					(size 1.27 1.27)
				)
				(justify left bottom)
				(hide yes)
			)
		)
		(property "Datasheet" "https://www.molex.com/content/dam/molex/molex-dot-com/products/automated/en-us/salesdrawingpdf/203/203456/2034560003_sd.pdf?inline"
			(at 395.224 44.958 0)
			(effects
				(font
					(size 1.27 1.27)
				)
				(justify left bottom)
				(hide yes)
			)
		)
		(property "Description" "Mirror Mezz Hermaphroditic Connector, 5.50mm Connector Height, BGA-Attach Mounting, 7 Pair, 11 Row, 699 Circuits, 0.76µm Gold Plating, without Pegs"
			(at 395.224 53.594 0)
			(effects
				(font
					(size 1.27 1.27)
				)
				(justify left bottom)
				(hide yes)
			)
		)
		(property "MPN" "203456-0003"
			(at 342.265 29.21 0)
			(effects
				(font
					(size 1.27 1.27)
				)
			)
		)
		(property "Manufacturer" "Molex"
			(at 395.224 47.244 0)
			(effects
				(font
					(size 1.27 1.27)
				)
				(justify left bottom)
				(hide yes)
			)
		)
		(property "Author" "Antmicro"
			(at 395.224 49.276 0)
			(effects
				(font
					(size 1.27 1.27)
				)
				(justify left bottom)
				(hide yes)
			)
		)
		(property "License" "Apache-2.0"
			(at 395.224 51.308 0)
			(effects
				(font
					(size 1.27 1.27)
				)
				(justify left bottom)
				(hide yes)
			)
		)
		(pin "L27"
		)
		(pin "A33"
		)
		(pin "J65"
		)
		(pin "A29"
		)
		(pin "D63"
		)
		(pin "G2"
		)
		(pin "J64"
		)
		(pin "F65"
		)
		(pin "D64"
		)
		(pin "L22"
		)
		(pin "D2"
		)
		(pin "G33"
		)
		(pin "F3"
		)
		(pin "H64"
		)
		(pin "H3"
		)
		(pin "G65"
		)
		(pin "F1"
		)
		(pin "J63"
		)
		(pin "D65"
		)
		(pin "B44"
		)
		(pin "F11"
		)
		(pin "B39"
		)
		(pin "E36"
		)
		(pin "B11"
		)
		(pin "D57"
		)
		(pin "E21"
		)
		(pin "E28"
		)
		(pin "E24"
		)
		(pin "E12"
		)
		(pin "C9"
		)
		(pin "D39"
		)
		(pin "E65"
		)
		(pin "H1"
		)
		(pin "D3"
		)
		(pin "H2"
		)
		(pin "F51"
		)
		(pin "A55"
		)
		(pin "J2"
		)
		(pin "F63"
		)
		(pin "L55"
		)
		(pin "B19"
		)
		(pin "B38"
		)
		(pin "E32"
		)
		(pin "G36"
		)
		(pin "E37"
		)
		(pin "E64"
		)
		(pin "L23"
		)
		(pin "A46"
		)
		(pin "H65"
		)
		(pin "C55"
		)
		(pin "B53"
		)
		(pin "C13"
		)
		(pin "C34"
		)
		(pin "C35"
		)
		(pin "F19"
		)
		(pin "L47"
		)
		(pin "C63"
		)
		(pin "E46"
		)
		(pin "C29"
		)
		(pin "H31"
		)
		(pin "D37"
		)
		(pin "H41"
		)
		(pin "J32"
		)
		(pin "G5"
		)
		(pin "B55"
		)
		(pin "L60"
		)
		(pin "B10"
		)
		(pin "K52"
		)
		(pin "K51"
		)
		(pin "E6"
		)
		(pin "F44"
		)
		(pin "C23"
		)
		(pin "C22"
		)
		(pin "L42"
		)
		(pin "E29"
		)
		(pin "A16"
		)
		(pin "E16"
		)
		(pin "D7"
		)
		(pin "K15"
		)
		(pin "L31"
		)
		(pin "G62"
		)
		(pin "F6"
		)
		(pin "H16"
		)
		(pin "G18"
		)
		(pin "F4"
		)
		(pin "C12"
		)
		(pin "K31"
		)
		(pin "B7"
		)
		(pin "B57"
		)
		(pin "E2"
		)
		(pin "F14"
		)
		(pin "A9"
		)
		(pin "E52"
		)
		(pin "H56"
		)
		(pin "A37"
		)
		(pin "D34"
		)
		(pin "E62"
		)
		(pin "H34"
		)
		(pin "D41"
		)
		(pin "F15"
		)
		(pin "A32"
		)
		(pin "B35"
		)
		(pin "D4"
		)
		(pin "D26"
		)
		(pin "G13"
		)
		(pin "B41"
		)
		(pin "B30"
		)
		(pin "F23"
		)
		(pin "A12"
		)
		(pin "L20"
		)
		(pin "J29"
		)
		(pin "G63"
		)
		(pin "A22"
		)
		(pin "A23"
		)
		(pin "H35"
		)
		(pin "K34"
		)
		(pin "L13"
		)
		(pin "K35"
		)
		(pin "J3"
		)
		(pin "C49"
		)
		(pin "L53"
		)
		(pin "J36"
		)
		(pin "D15"
		)
		(pin "E33"
		)
		(pin "G32"
		)
		(pin "A63"
		)
		(pin "L12"
		)
		(pin "B50"
		)
		(pin "C33"
		)
		(pin "D38"
		)
		(pin "G29"
		)
		(pin "L51"
		)
		(pin "H54"
		)
		(pin "K53"
		)
		(pin "K54"
		)
		(pin "L61"
		)
		(pin "L58"
		)
		(pin "G3"
		)
		(pin "G43"
		)
		(pin "C28"
		)
		(pin "L8"
		)
		(pin "J61"
		)
		(pin "D40"
		)
		(pin "B40"
		)
		(pin "K36"
		)
		(pin "D44"
		)
		(pin "F27"
		)
		(pin "D53"
		)
		(pin "K19"
		)
		(pin "J57"
		)
		(pin "A56"
		)
		(pin "D55"
		)
		(pin "K8"
		)
		(pin "L16"
		)
		(pin "J12"
		)
		(pin "D23"
		)
		(pin "F34"
		)
		(pin "H4"
		)
		(pin "F54"
		)
		(pin "G55"
		)
		(pin "K7"
		)
		(pin "H9"
		)
		(pin "L14"
		)
		(pin "G39"
			(alternate "CAN0_DIN")
		)
		(pin "G38"
			(alternate "CAN0_DOUT")
		)
		(pin "H36"
			(alternate "CAN1_DIN")
		)
		(pin "H37"
			(alternate "CAN1_DOUT")
		)
		(pin "K40"
		)
		(pin "K45"
		)
		(pin "F10"
		)
		(pin "F9"
		)
		(pin "C39"
		)
		(pin "A58"
		)
		(pin "F49"
		)
		(pin "G48"
		)
		(pin "G47"
		)
		(pin "K42"
		)
		(pin "G23"
		)
		(pin "G22"
		)
		(pin "H10"
		)
		(pin "L18"
		)
		(pin "L26"
		)
		(pin "L34"
		)
		(pin "G37"
		)
		(pin "H60"
		)
		(pin "C61"
		)
		(pin "A62"
		)
		(pin "G7"
		)
		(pin "L15"
		)
		(pin "J56"
		)
		(pin "F26"
		)
		(pin "H15"
		)
		(pin "H40"
		)
		(pin "J20"
		)
		(pin "F7"
		)
		(pin "D8"
		)
		(pin "C7"
		)
		(pin "H8"
		)
		(pin "L9"
		)
		(pin "L48"
		)
		(pin "J54"
		)
		(pin "J28"
		)
		(pin "B16"
		)
		(pin "B17"
		)
		(pin "K39"
		)
		(pin "B51"
		)
		(pin "B52"
		)
		(pin "A13"
		)
		(pin "E3"
		)
		(pin "B14"
		)
		(pin "B42"
		)
		(pin "A41"
		)
		(pin "A42"
		)
		(pin "D22"
		)
		(pin "G15"
		)
		(pin "G14"
		)
		(pin "A52"
		)
		(pin "C21"
		)
		(pin "G52"
		)
		(pin "K62"
		)
		(pin "E58"
		)
		(pin "B60"
		)
		(pin "A60"
		)
		(pin "J21"
		)
		(pin "K22"
		)
		(pin "J4"
		)
		(pin "B59"
		)
		(pin "A59"
		)
		(pin "B62"
		)
		(pin "H32"
		)
		(pin "H33"
		)
		(pin "K50"
		)
		(pin "D19"
		)
		(pin "H28"
		)
		(pin "H29"
		)
		(pin "B34"
		)
		(pin "H22"
		)
		(pin "H49"
		)
		(pin "H48"
		)
		(pin "L36"
		)
		(pin "L37"
		)
		(pin "J37"
		)
		(pin "F30"
		)
		(pin "H24"
		)
		(pin "H25"
		)
		(pin "A3"
		)
		(pin "G4"
		)
		(pin "E4"
		)
		(pin "F5"
		)
		(pin "G51"
		)
		(pin "G50"
		)
		(pin "B47"
		)
		(pin "C16"
		)
		(pin "G40"
		)
		(pin "C43"
		)
		(pin "J34"
		)
		(pin "A34"
		)
		(pin "A35"
		)
		(pin "L30"
		)
		(pin "B27"
		)
		(pin "G64"
		)
		(pin "K23"
		)
		(pin "G17"
		)
		(pin "F16"
		)
		(pin "F17"
		)
		(pin "H19"
		)
		(pin "G12"
		)
		(pin "B12"
		)
		(pin "B13"
		)
		(pin "J24"
		)
		(pin "E9"
		)
		(pin "L17"
		)
		(pin "L32"
		)
		(pin "L33"
		)
		(pin "F32"
		)
		(pin "F33"
		)
		(pin "K38"
		)
		(pin "E63"
		)
		(pin "F64"
		)
		(pin "E1"
		)
		(pin "G24"
		)
		(pin "D1"
		)
		(pin "F18"
		)
		(pin "H51"
		)
		(pin "J52"
		)
		(pin "F39"
		)
		(pin "J43"
		)
		(pin "E15"
		)
		(pin "E14"
		)
		(pin "L24"
		)
		(pin "H5"
		)
		(pin "K6"
		)
		(pin "J5"
		)
		(pin "J6"
		)
		(pin "L59"
		)
		(pin "K3"
		)
		(pin "D28"
		)
		(pin "D29"
		)
		(pin "C25"
		)
		(pin "A15"
		)
		(pin "A14"
		)
		(pin "K30"
		)
		(pin "D35"
		)
		(pin "J46"
		)
		(pin "F57"
		)
		(pin "F42"
		)
		(pin "E42"
		)
		(pin "E41"
		)
		(pin "A24"
		)
		(pin "C46"
		)
		(pin "J60"
		)
		(pin "F61"
		)
		(pin "H27"
		)
		(pin "B18"
		)
		(pin "A43"
		)
		(pin "D27"
		)
		(pin "H14"
		)
		(pin "A17"
		)
		(pin "F24"
		)
		(pin "F25"
		)
		(pin "A51"
		)
		(pin "A50"
		)
		(pin "C51"
		)
		(pin "C50"
		)
		(pin "C1"
		)
		(pin "J22"
		)
		(pin "J23"
		)
		(pin "C2"
		)
		(pin "B3"
		)
		(pin "G35"
		)
		(pin "G34"
		)
		(pin "B63"
		)
		(pin "A28"
		)
		(pin "B31"
		)
		(pin "C64"
		)
		(pin "C60"
		)
		(pin "K59"
		)
		(pin "J59"
		)
		(pin "C42"
		)
		(pin "C41"
		)
		(pin "F46"
		)
		(pin "K26"
		)
		(pin "D49"
		)
		(pin "D48"
		)
		(pin "G58"
		)
		(pin "A57"
		)
		(pin "C58"
		)
		(pin "C56"
		)
		(pin "D46"
		)
		(pin "D45"
		)
		(pin "J44"
		)
		(pin "K46"
		)
		(pin "K47"
		)
		(pin "J47"
		)
		(pin "J48"
		)
		(pin "D14"
		)
		(pin "F20"
		)
		(pin "F21"
		)
		(pin "F43"
		)
		(pin "J62"
		)
		(pin "B21"
		)
		(pin "B20"
		)
		(pin "E47"
		)
		(pin "E48"
		)
		(pin "C44"
		)
		(pin "H17"
		)
		(pin "G19"
		)
		(pin "C59"
		)
		(pin "F60"
		)
		(pin "C57"
		)
		(pin "E56"
		)
		(pin "J53"
		)
		(pin "K5"
		)
		(pin "G31"
		)
		(pin "G30"
		)
		(pin "D11"
		)
		(pin "H44"
		)
		(pin "L46"
		)
		(pin "L7"
		)
		(pin "L25"
		)
		(pin "B23"
		)
		(pin "F58"
		)
		(pin "D59"
		)
		(pin "B61"
		)
		(pin "H61"
		)
		(pin "J41"
		)
		(pin "J42"
		)
		(pin "B43"
		)
		(pin "B29"
		)
		(pin "B28"
		)
		(pin "D51"
		)
		(pin "D52"
		)
		(pin "F62"
		)
		(pin "E51"
		)
		(pin "E50"
		)
		(pin "K56"
		)
		(pin "K55"
		)
		(pin "F45"
		)
		(pin "E45"
		)
		(pin "E44"
		)
		(pin "A8"
		)
		(pin "K49"
		)
		(pin "K21"
		)
		(pin "K20"
		)
		(pin "E13"
		)
		(pin "C52"
		)
		(pin "H26"
		)
		(pin "J49"
		)
		(pin "D47"
		)
		(pin "B25"
		)
		(pin "B24"
		)
		(pin "L28"
		)
		(pin "K4"
		)
		(pin "D20"
		)
		(pin "D21"
		)
		(pin "E25"
		)
		(pin "G20"
		)
		(pin "H42"
		)
		(pin "G41"
		)
		(pin "G42"
		)
		(pin "L10"
		)
		(pin "L11"
		)
		(pin "H23"
		)
		(pin "B37"
		)
		(pin "E11"
		)
		(pin "H63"
		)
		(pin "E34"
		)
		(pin "F37"
		)
		(pin "F36"
		)
		(pin "E35"
		)
		(pin "E7"
		)
		(pin "F8"
		)
		(pin "A4"
		)
		(pin "J26"
		)
		(pin "J27"
		)
		(pin "L35"
		)
		(pin "J11"
		)
		(pin "E27"
		)
		(pin "A21"
		)
		(pin "K18"
		)
		(pin "B33"
		)
		(pin "B32"
		)
		(pin "E60"
		)
		(pin "A53"
		)
		(pin "E23"
		)
		(pin "E22"
		)
		(pin "D50"
		)
		(pin "G57"
		)
		(pin "C53"
		)
		(pin "K10"
		)
		(pin "F22"
		)
		(pin "H20"
		)
		(pin "H21"
		)
		(pin "G11"
		)
		(pin "G10"
		)
		(pin "B26"
		)
		(pin "J16"
		)
		(pin "J40"
		)
		(pin "K14"
		)
		(pin "G8"
		)
		(pin "C8"
		)
		(pin "B58"
		)
		(pin "H52"
		)
		(pin "C38"
		)
		(pin "A18"
		)
		(pin "G49"
		)
		(pin "J55"
		)
		(pin "A47"
		)
		(pin "A40"
		)
		(pin "L52"
		)
		(pin "A6"
		)
		(pin "J13"
		)
		(pin "B22"
		)
		(pin "G16"
		)
		(pin "F38"
		)
		(pin "F2"
		)
		(pin "F50"
		)
		(pin "H7"
		)
		(pin "F35"
		)
		(pin "G1"
		)
		(pin "K13"
		)
		(pin "K12"
		)
		(pin "G46"
		)
		(pin "J58"
		)
		(pin "H58"
		)
		(pin "K57"
		)
		(pin "E54"
		)
		(pin "G21"
		)
		(pin "D16"
		)
		(pin "D17"
		)
		(pin "A19"
		)
		(pin "A38"
		)
		(pin "E5"
		)
		(pin "B54"
		)
		(pin "A54"
		)
		(pin "E39"
		)
		(pin "E38"
		)
		(pin "H43"
		)
		(pin "K17"
		)
		(pin "K16"
		)
		(pin "J45"
		)
		(pin "K44"
		)
		(pin "K43"
		)
		(pin "D58"
		)
		(pin "G61"
		)
		(pin "H59"
		)
		(pin "G60"
		)
		(pin "F41"
		)
		(pin "H11"
		)
		(pin "C6"
		)
		(pin "G59"
		)
		(pin "E53"
		)
		(pin "D61"
		)
		(pin "L56"
		)
		(pin "A61"
		)
		(pin "C31"
		)
		(pin "C30"
		)
		(pin "K41"
		)
		(pin "K63"
		)
		(pin "H47"
		)
		(pin "D18"
		)
		(pin "L54"
		)
		(pin "L62"
		)
		(pin "K11"
		)
		(pin "G27"
		)
		(pin "G26"
		)
		(pin "D10"
		)
		(pin "J9"
		)
		(pin "C20"
		)
		(pin "L19"
		)
		(pin "B36"
		)
		(pin "L39"
		)
		(pin "C62"
		)
		(pin "C17"
		)
		(pin "C32"
		)
		(pin "A48"
		)
		(pin "H55"
		)
		(pin "B8"
		)
		(pin "L50"
		)
		(pin "L49"
		)
		(pin "F31"
		)
		(pin "H62"
		)
		(pin "K60"
		)
		(pin "L4"
		)
		(pin "L6"
		)
		(pin "C54"
		)
		(pin "D54"
		)
		(pin "J51"
		)
		(pin "J33"
		)
		(pin "F56"
		)
		(pin "A39"
		)
		(pin "E59"
		)
		(pin "F59"
		)
		(pin "L57"
		)
		(pin "L44"
		)
		(pin "F12"
		)
		(pin "F13"
		)
		(pin "D30"
		)
		(pin "C45"
		)
		(pin "D42"
		)
		(pin "D43"
		)
		(pin "A25"
		)
		(pin "H38"
		)
		(pin "K37"
		)
		(pin "L41"
		)
		(pin "C37"
		)
		(pin "G28"
		)
		(pin "E43"
		)
		(pin "J1"
		)
		(pin "J17"
		)
		(pin "D33"
		)
		(pin "D32"
		)
		(pin "J35"
		)
		(pin "H18"
		)
		(pin "E20"
		)
		(pin "L5"
		)
		(pin "H6"
		)
		(pin "K58"
		)
		(pin "H57"
		)
		(pin "B15"
		)
		(pin "J38"
		)
		(pin "J39"
		)
		(pin "D36"
		)
		(pin "H50"
		)
		(pin "B48"
		)
		(pin "B49"
		)
		(pin "B9"
		)
		(pin "F47"
		)
		(pin "E57"
		)
		(pin "D31"
		)
		(pin "E30"
		)
		(pin "D9"
		)
		(pin "B5"
		)
		(pin "E49"
		)
		(pin "C3"
		)
		(pin "A30"
		)
		(pin "A31"
		)
		(pin "E19"
		)
		(pin "E18"
		)
		(pin "C19"
		)
		(pin "C36"
		)
		(pin "K48"
		)
		(pin "J10"
		)
		(pin "K9"
		)
		(pin "E31"
		)
		(pin "F55"
		)
		(pin "D56"
		)
		(pin "G56"
		)
		(pin "G44"
		)
		(pin "G45"
		)
		(pin "F48"
		)
		(pin "J7"
		)
		(pin "J19"
		)
		(pin "C47"
		)
		(pin "C48"
		)
		(pin "F40"
		)
		(pin "D24"
		)
		(pin "D25"
		)
		(pin "K61"
		)
		(pin "F53"
		)
		(pin "D60"
		)
		(pin "E61"
		)
		(pin "D62"
		)
		(pin "L40"
		)
		(pin "L43"
		)
		(pin "L63"
		)
		(pin "K27"
		)
		(pin "B46"
		)
		(pin "A44"
		)
		(pin "A45"
		)
		(pin "B4"
		)
		(pin "G25"
		)
		(pin "L29"
		)
		(pin "L3"
		)
		(pin "K25"
		)
		(pin "K24"
		)
		(pin "A26"
		)
		(pin "A27"
		)
		(pin "H39"
		)
		(pin "E17"
		)
		(pin "G9"
		)
		(pin "C4"
		)
		(pin "D5"
		)
		(pin "G6"
		)
		(pin "J18"
		)
		(pin "E26"
		)
		(pin "F52"
		)
		(pin "H12"
		)
		(pin "H13"
		)
		(pin "A10"
		)
		(pin "A11"
		)
		(pin "K29"
		)
		(pin "K28"
		)
		(pin "A7"
		)
		(pin "E10"
		)
		(pin "C5"
		)
		(pin "D6"
		)
		(pin "B6"
		)
		(pin "A5"
		)
		(pin "E8"
		)
		(pin "A49"
		)
		(pin "A36"
		)
		(pin "H46"
		)
		(pin "H45"
		)
		(pin "B45"
		)
		(pin "J30"
		)
		(pin "J31"
		)
		(pin "C15"
		)
		(pin "C14"
		)
		(pin "J14"
		)
		(pin "J15"
		)
		(pin "C27"
		)
		(pin "C26"
		)
		(pin "K32"
		)
		(pin "K33"
		)
		(pin "J8"
		)
		(pin "J25"
		)
		(pin "L38"
		)
		(pin "C40"
		)
		(pin "D12"
		)
		(pin "D13"
		)
		(pin "A20"
		)
		(pin "H30"
		)
		(pin "E40"
		)
		(pin "L21"
		)
		(pin "H53"
		)
		(pin "E55"
		)
		(pin "B56"
		)
		(pin "F28"
		)
		(pin "F29"
		)
		(pin "C11"
		)
		(pin "C10"
		)
		(pin "L45"
		)
		(pin "J50"
		)
		(pin "C65"
		)
		(pin "G53"
		)
		(pin "G54"
		)
		(pin "C18"
		)
		(pin "C24"
		)
		(instances
			(project ""
				(path ""
					(reference "J1")
					(unit 9)
				)
			)
		)
	)
	(symbol
		(lib_id "antmicropower:GND")
		(at 83.82 121.92 0)
		(mirror y)
		(unit 1)
		(exclude_from_sim no)
		(in_bom yes)
		(on_board yes)
		(dnp no)
		(property "Reference" "#PWR0685"
			(at 83.82 128.27 0)
			(effects
				(font
					(size 1.27 1.27)
				)
				(justify left bottom)
				(hide yes)
			)
		)
		(property "Value" "GND"
			(at 83.82 125.73 0)
			(effects
				(font
					(size 1.27 1.27)
					(thickness 0.15)
				)
			)
		)
		(property "Footprint" ""
			(at 74.93 129.54 0)
			(effects
				(font
					(size 1.27 1.27)
					(thickness 0.15)
				)
				(justify left bottom)
				(hide yes)
			)
		)
		(property "Datasheet" ""
			(at 74.93 134.62 0)
			(effects
				(font
					(size 1.27 1.27)
					(thickness 0.15)
				)
				(justify left bottom)
				(hide yes)
			)
		)
		(property "Description" ""
			(at 83.82 121.92 0)
			(effects
				(font
					(size 1.27 1.27)
				)
				(hide yes)
			)
		)
		(property "Author" "Antmicro"
			(at 74.93 129.54 0)
			(effects
				(font
					(size 1.27 1.27)
					(thickness 0.15)
				)
				(justify left bottom)
				(hide yes)
			)
		)
		(property "License" "Apache-2.0"
			(at 74.93 132.08 0)
			(effects
				(font
					(size 1.27 1.27)
					(thickness 0.15)
				)
				(justify left bottom)
				(hide yes)
			)
		)
		(pin "1"
		)
		(instances
			(project "jetson-agx-thor-baseboard"
				(path ""
					(reference "#PWR0685")
					(unit 1)
				)
			)
		)
	)
	(symbol
		(lib_id "antmicropower:+1V8")
		(at 57.15 43.18 0)
		(unit 1)
		(exclude_from_sim no)
		(in_bom yes)
		(on_board yes)
		(dnp no)
		(property "Reference" "#PWR0760"
			(at 57.15 46.99 0)
			(effects
				(font
					(size 1.27 1.27)
				)
				(justify left bottom)
				(hide yes)
			)
		)
		(property "Value" "+1V8"
			(at 53.975 39.37 0)
			(effects
				(font
					(size 1.27 1.27)
					(thickness 0.15)
				)
				(justify left)
			)
		)
		(property "Footprint" ""
			(at 72.39 50.8 0)
			(effects
				(font
					(size 1.27 1.27)
					(thickness 0.15)
				)
				(justify left bottom)
				(hide yes)
			)
		)
		(property "Datasheet" ""
			(at 72.39 53.34 0)
			(effects
				(font
					(size 1.27 1.27)
					(thickness 0.15)
				)
				(justify left bottom)
				(hide yes)
			)
		)
		(property "Description" ""
			(at 57.15 43.18 0)
			(effects
				(font
					(size 1.27 1.27)
				)
				(hide yes)
			)
		)
		(property "Author" "Antmicro"
			(at 72.39 48.26 0)
			(effects
				(font
					(size 1.27 1.27)
					(thickness 0.15)
				)
				(justify left bottom)
				(hide yes)
			)
		)
		(property "License" "Apache-2.0"
			(at 72.39 50.8 0)
			(effects
				(font
					(size 1.27 1.27)
					(thickness 0.15)
				)
				(justify left bottom)
				(hide yes)
			)
		)
		(pin "1"
		)
		(instances
			(project "jetson-agx-thor-baseboard"
				(path ""
					(reference "#PWR0760")
					(unit 1)
				)
			)
		)
	)
	(symbol
		(lib_id "antmicroResistors0402:R_2k2_0402")
		(at 115.57 49.53 270)
		(unit 1)
		(exclude_from_sim no)
		(in_bom yes)
		(on_board yes)
		(dnp no)
		(fields_autoplaced yes)
		(property "Reference" "R360"
			(at 118.11 50.8 90)
			(effects
				(font
					(size 1.27 1.27)
					(thickness 0.15)
				)
				(justify left)
			)
		)
		(property "Value" "R_2k2_0402"
			(at 102.87 69.85 0)
			(effects
				(font
					(size 1.27 1.27)
					(thickness 0.15)
				)
				(justify left bottom)
				(hide yes)
			)
		)
		(property "Footprint" "antmicro-footprints:R_0402_1005Metric"
			(at 100.33 69.85 0)
			(effects
				(font
					(size 1.27 1.27)
					(thickness 0.15)
				)
				(justify left bottom)
				(hide yes)
			)
		)
		(property "Datasheet" "https://www.bourns.com/docs/product-datasheets/cr.pdf"
			(at 97.79 69.85 0)
			(effects
				(font
					(size 1.27 1.27)
					(thickness 0.15)
				)
				(justify left bottom)
				(hide yes)
			)
		)
		(property "Description" "SMD Chip Resistor, 2.2 kohm, ± 1%, 62.5 mW, 0402 [1005 Metric], Thick Film, General Purpose"
			(at 85.09 69.85 0)
			(effects
				(font
					(size 1.27 1.27)
				)
				(justify left bottom)
				(hide yes)
			)
		)
		(property "MPN" "CR0402-FX-2201GLF"
			(at 95.25 69.85 0)
			(effects
				(font
					(size 1.27 1.27)
					(thickness 0.15)
				)
				(justify left bottom)
				(hide yes)
			)
		)
		(property "Manufacturer" "Bourns"
			(at 92.71 69.85 0)
			(effects
				(font
					(size 1.27 1.27)
					(thickness 0.15)
				)
				(justify left bottom)
				(hide yes)
			)
		)
		(property "License" "Apache-2.0"
			(at 90.17 69.85 0)
			(effects
				(font
					(size 1.27 1.27)
					(thickness 0.15)
				)
				(justify left bottom)
				(hide yes)
			)
		)
		(property "Author" "Antmicro"
			(at 87.63 69.85 0)
			(effects
				(font
					(size 1.27 1.27)
					(thickness 0.15)
				)
				(justify left bottom)
				(hide yes)
			)
		)
		(property "Val" "2k2"
			(at 118.11 53.34 90)
			(effects
				(font
					(size 1.27 1.27)
					(thickness 0.15)
				)
				(justify left)
			)
		)
		(property "Tolerance" "1%"
			(at 105.41 69.85 0)
			(effects
				(font
					(size 1.27 1.27)
				)
				(justify left bottom)
				(hide yes)
			)
		)
		(pin "2"
		)
		(pin "1"
		)
		(instances
			(project "jetson-agx-thor-baseboard"
				(path ""
					(reference "R360")
					(unit 1)
				)
			)
		)
	)
	(symbol
		(lib_id "antmicropower:GND")
		(at 106.68 186.69 0)
		(unit 1)
		(exclude_from_sim no)
		(in_bom yes)
		(on_board yes)
		(dnp no)
		(property "Reference" "#PWR0727"
			(at 106.68 193.04 0)
			(effects
				(font
					(size 1.27 1.27)
				)
				(justify left bottom)
				(hide yes)
			)
		)
		(property "Value" "GND"
			(at 106.68 190.5 0)
			(effects
				(font
					(size 1.27 1.27)
					(thickness 0.15)
				)
			)
		)
		(property "Footprint" ""
			(at 115.57 194.31 0)
			(effects
				(font
					(size 1.27 1.27)
					(thickness 0.15)
				)
				(justify left bottom)
				(hide yes)
			)
		)
		(property "Datasheet" ""
			(at 115.57 199.39 0)
			(effects
				(font
					(size 1.27 1.27)
					(thickness 0.15)
				)
				(justify left bottom)
				(hide yes)
			)
		)
		(property "Description" ""
			(at 106.68 186.69 0)
			(effects
				(font
					(size 1.27 1.27)
				)
				(hide yes)
			)
		)
		(property "Author" "Antmicro"
			(at 115.57 194.31 0)
			(effects
				(font
					(size 1.27 1.27)
					(thickness 0.15)
				)
				(justify left bottom)
				(hide yes)
			)
		)
		(property "License" "Apache-2.0"
			(at 115.57 196.85 0)
			(effects
				(font
					(size 1.27 1.27)
					(thickness 0.15)
				)
				(justify left bottom)
				(hide yes)
			)
		)
		(pin "1"
		)
		(instances
			(project "jetson-agx-thor-baseboard"
				(path ""
					(reference "#PWR0727")
					(unit 1)
				)
			)
		)
	)
	(symbol
		(lib_id "antmicropower:GND")
		(at 77.47 210.82 0)
		(unit 1)
		(exclude_from_sim no)
		(in_bom yes)
		(on_board yes)
		(dnp no)
		(property "Reference" "#PWR019"
			(at 77.47 217.17 0)
			(effects
				(font
					(size 1.27 1.27)
				)
				(justify left bottom)
				(hide yes)
			)
		)
		(property "Value" "GND"
			(at 77.47 214.63 0)
			(effects
				(font
					(size 1.27 1.27)
					(thickness 0.15)
				)
			)
		)
		(property "Footprint" ""
			(at 86.36 218.44 0)
			(effects
				(font
					(size 1.27 1.27)
					(thickness 0.15)
				)
				(justify left bottom)
				(hide yes)
			)
		)
		(property "Datasheet" ""
			(at 86.36 223.52 0)
			(effects
				(font
					(size 1.27 1.27)
					(thickness 0.15)
				)
				(justify left bottom)
				(hide yes)
			)
		)
		(property "Description" ""
			(at 77.47 210.82 0)
			(effects
				(font
					(size 1.27 1.27)
				)
				(hide yes)
			)
		)
		(property "Author" "Antmicro"
			(at 86.36 218.44 0)
			(effects
				(font
					(size 1.27 1.27)
					(thickness 0.15)
				)
				(justify left bottom)
				(hide yes)
			)
		)
		(property "License" "Apache-2.0"
			(at 86.36 220.98 0)
			(effects
				(font
					(size 1.27 1.27)
					(thickness 0.15)
				)
				(justify left bottom)
				(hide yes)
			)
		)
		(pin "1"
		)
		(instances
			(project "jetson-agx-thor-baseboard"
				(path ""
					(reference "#PWR019")
					(unit 1)
				)
			)
		)
	)
	(symbol
		(lib_id "antmicropower:+1V8")
		(at 83.82 104.14 0)
		(unit 1)
		(exclude_from_sim no)
		(in_bom yes)
		(on_board yes)
		(dnp no)
		(property "Reference" "#PWR016"
			(at 83.82 107.95 0)
			(effects
				(font
					(size 1.27 1.27)
				)
				(justify left bottom)
				(hide yes)
			)
		)
		(property "Value" "+1V8"
			(at 80.645 100.33 0)
			(effects
				(font
					(size 1.27 1.27)
					(thickness 0.15)
				)
				(justify left)
			)
		)
		(property "Footprint" ""
			(at 99.06 111.76 0)
			(effects
				(font
					(size 1.27 1.27)
					(thickness 0.15)
				)
				(justify left bottom)
				(hide yes)
			)
		)
		(property "Datasheet" ""
			(at 99.06 114.3 0)
			(effects
				(font
					(size 1.27 1.27)
					(thickness 0.15)
				)
				(justify left bottom)
				(hide yes)
			)
		)
		(property "Description" ""
			(at 83.82 104.14 0)
			(effects
				(font
					(size 1.27 1.27)
				)
				(hide yes)
			)
		)
		(property "Author" "Antmicro"
			(at 99.06 109.22 0)
			(effects
				(font
					(size 1.27 1.27)
					(thickness 0.15)
				)
				(justify left bottom)
				(hide yes)
			)
		)
		(property "License" "Apache-2.0"
			(at 99.06 111.76 0)
			(effects
				(font
					(size 1.27 1.27)
					(thickness 0.15)
				)
				(justify left bottom)
				(hide yes)
			)
		)
		(pin "1"
		)
		(instances
			(project "jetson-agx-thor-baseboard"
				(path ""
					(reference "#PWR016")
					(unit 1)
				)
			)
		)
	)
	(symbol
		(lib_id "antmicropower:+3V3")
		(at 113.03 201.93 0)
		(unit 1)
		(exclude_from_sim no)
		(in_bom yes)
		(on_board yes)
		(dnp no)
		(property "Reference" "#PWR0700"
			(at 113.03 205.74 0)
			(effects
				(font
					(size 1.27 1.27)
				)
				(justify left bottom)
				(hide yes)
			)
		)
		(property "Value" "+3V3"
			(at 109.855 198.12 0)
			(effects
				(font
					(size 1.27 1.27)
					(thickness 0.15)
				)
				(justify left)
			)
		)
		(property "Footprint" ""
			(at 128.27 209.55 0)
			(effects
				(font
					(size 1.27 1.27)
					(thickness 0.15)
				)
				(justify left bottom)
				(hide yes)
			)
		)
		(property "Datasheet" ""
			(at 128.27 212.09 0)
			(effects
				(font
					(size 1.27 1.27)
					(thickness 0.15)
				)
				(justify left bottom)
				(hide yes)
			)
		)
		(property "Description" ""
			(at 113.03 201.93 0)
			(effects
				(font
					(size 1.27 1.27)
				)
				(hide yes)
			)
		)
		(property "Author" "Antmicro"
			(at 128.27 204.47 0)
			(effects
				(font
					(size 1.27 1.27)
					(thickness 0.15)
				)
				(justify left bottom)
				(hide yes)
			)
		)
		(property "License" "Apache-2.0"
			(at 128.27 207.01 0)
			(effects
				(font
					(size 1.27 1.27)
					(thickness 0.15)
				)
				(justify left bottom)
				(hide yes)
			)
		)
		(pin "1"
		)
		(instances
			(project "jetson-agx-thor-baseboard"
				(path ""
					(reference "#PWR0700")
					(unit 1)
				)
			)
		)
	)
	(symbol
		(lib_id "antmicropower:+3V3")
		(at 113.03 138.43 0)
		(unit 1)
		(exclude_from_sim no)
		(in_bom yes)
		(on_board yes)
		(dnp no)
		(property "Reference" "#PWR0732"
			(at 113.03 142.24 0)
			(effects
				(font
					(size 1.27 1.27)
				)
				(justify left bottom)
				(hide yes)
			)
		)
		(property "Value" "+3V3"
			(at 109.855 134.62 0)
			(effects
				(font
					(size 1.27 1.27)
					(thickness 0.15)
				)
				(justify left)
			)
		)
		(property "Footprint" ""
			(at 128.27 146.05 0)
			(effects
				(font
					(size 1.27 1.27)
					(thickness 0.15)
				)
				(justify left bottom)
				(hide yes)
			)
		)
		(property "Datasheet" ""
			(at 128.27 148.59 0)
			(effects
				(font
					(size 1.27 1.27)
					(thickness 0.15)
				)
				(justify left bottom)
				(hide yes)
			)
		)
		(property "Description" ""
			(at 113.03 138.43 0)
			(effects
				(font
					(size 1.27 1.27)
				)
				(hide yes)
			)
		)
		(property "Author" "Antmicro"
			(at 128.27 140.97 0)
			(effects
				(font
					(size 1.27 1.27)
					(thickness 0.15)
				)
				(justify left bottom)
				(hide yes)
			)
		)
		(property "License" "Apache-2.0"
			(at 128.27 143.51 0)
			(effects
				(font
					(size 1.27 1.27)
					(thickness 0.15)
				)
				(justify left bottom)
				(hide yes)
			)
		)
		(pin "1"
		)
		(instances
			(project "jetson-agx-thor-baseboard"
				(path ""
					(reference "#PWR0732")
					(unit 1)
				)
			)
		)
	)
	(symbol
		(lib_id "antmicroTestPoints:TP_0.75mm_SMD")
		(at 304.8 158.75 0)
		(mirror y)
		(unit 1)
		(exclude_from_sim no)
		(in_bom no)
		(on_board yes)
		(dnp no)
		(property "Reference" "TP103"
			(at 300.482 158.75 0)
			(effects
				(font
					(size 1.27 1.27)
				)
				(justify left)
			)
		)
		(property "Value" "TP_0.75mm_SMD"
			(at 294.64 162.56 0)
			(effects
				(font
					(size 1.27 1.27)
					(thickness 0.15)
				)
				(justify left bottom)
				(hide yes)
			)
		)
		(property "Footprint" "antmicro-footprints:TP_SMD_0.75mm"
			(at 294.64 165.1 0)
			(effects
				(font
					(size 1.27 1.27)
					(thickness 0.15)
				)
				(justify left bottom)
				(hide yes)
			)
		)
		(property "Datasheet" ""
			(at 287.02 171.45 0)
			(effects
				(font
					(size 1.27 1.27)
					(thickness 0.15)
				)
				(justify left bottom)
				(hide yes)
			)
		)
		(property "Description" "SMT test point"
			(at 304.8 158.75 0)
			(effects
				(font
					(size 1.27 1.27)
				)
				(hide yes)
			)
		)
		(property "MPN" ""
			(at 294.005 170.18 0)
			(effects
				(font
					(size 1.27 1.27)
					(thickness 0.15)
				)
				(justify left bottom)
				(hide yes)
			)
		)
		(property "Manufacturer" ""
			(at 294.005 165.1 0)
			(effects
				(font
					(size 1.27 1.27)
					(thickness 0.15)
				)
				(justify left bottom)
				(hide yes)
			)
		)
		(property "Author" "Antmicro"
			(at 294.64 167.64 0)
			(effects
				(font
					(size 1.27 1.27)
					(thickness 0.15)
				)
				(justify left bottom)
				(hide yes)
			)
		)
		(property "License" "Apache-2.0"
			(at 294.64 170.18 0)
			(effects
				(font
					(size 1.27 1.27)
					(thickness 0.15)
				)
				(justify left bottom)
				(hide yes)
			)
		)
		(pin "1"
		)
		(instances
			(project "jetson-agx-thor-baseboard"
				(path ""
					(reference "TP103")
					(unit 1)
				)
			)
		)
	)
	(symbol
		(lib_id "antmicroCapacitors0402:C_100n_0402")
		(at 113.03 146.05 270)
		(mirror x)
		(unit 1)
		(exclude_from_sim no)
		(in_bom yes)
		(on_board yes)
		(dnp no)
		(property "Reference" "C356"
			(at 114.935 142.24 90)
			(effects
				(font
					(size 1.27 1.27)
				)
				(justify left)
			)
		)
		(property "Value" "C_100n_0402"
			(at 102.87 125.73 0)
			(effects
				(font
					(size 1.27 1.27)
					(thickness 0.15)
				)
				(justify left bottom)
				(hide yes)
			)
		)
		(property "Footprint" "antmicro-footprints:C_0402_1005Metric"
			(at 100.33 125.73 0)
			(effects
				(font
					(size 1.27 1.27)
					(thickness 0.15)
				)
				(justify left bottom)
				(hide yes)
			)
		)
		(property "Datasheet" "https://www.murata.com/products/productdetail?partno=GRM155R61H104KE14%23"
			(at 97.79 125.73 0)
			(effects
				(font
					(size 1.27 1.27)
					(thickness 0.15)
				)
				(justify left bottom)
				(hide yes)
			)
		)
		(property "Description" "SMD Multilayer Ceramic Capacitor, 0.1 µF, 50 V, 0402 [1005 Metric], ± 10%, X5R, GRM Series"
			(at 113.03 146.05 0)
			(effects
				(font
					(size 1.27 1.27)
				)
				(hide yes)
			)
		)
		(property "Manufacturer" "Murata"
			(at 92.71 125.73 0)
			(effects
				(font
					(size 1.27 1.27)
					(thickness 0.15)
				)
				(justify left bottom)
				(hide yes)
			)
		)
		(property "MPN" "GRM155R61H104KE14D"
			(at 95.25 125.73 0)
			(effects
				(font
					(size 1.27 1.27)
					(thickness 0.15)
				)
				(justify left bottom)
				(hide yes)
			)
		)
		(property "Val" "100n"
			(at 114.935 144.78 90)
			(effects
				(font
					(size 1.27 1.27)
					(thickness 0.15)
				)
				(justify left)
			)
		)
		(property "License" "Apache-2.0"
			(at 90.17 125.73 0)
			(effects
				(font
					(size 1.27 1.27)
					(thickness 0.15)
				)
				(justify left bottom)
				(hide yes)
			)
		)
		(property "Author" "Antmicro"
			(at 87.63 125.73 0)
			(effects
				(font
					(size 1.27 1.27)
					(thickness 0.15)
				)
				(justify left bottom)
				(hide yes)
			)
		)
		(property "Voltage" "50V"
			(at 85.09 125.73 0)
			(effects
				(font
					(size 1.27 1.27)
				)
				(justify left bottom)
				(hide yes)
			)
		)
		(property "Dielectric" "X5R"
			(at 82.55 125.73 0)
			(effects
				(font
					(size 1.27 1.27)
				)
				(justify left bottom)
				(hide yes)
			)
		)
		(pin "1"
		)
		(pin "2"
		)
		(instances
			(project "jetson-agx-thor-baseboard"
				(path ""
					(reference "C356")
					(unit 1)
				)
			)
		)
	)
	(symbol
		(lib_id "antmicropower:GND")
		(at 100.33 92.71 0)
		(unit 1)
		(exclude_from_sim no)
		(in_bom yes)
		(on_board yes)
		(dnp no)
		(property "Reference" "#PWR04"
			(at 100.33 99.06 0)
			(effects
				(font
					(size 1.27 1.27)
				)
				(justify left bottom)
				(hide yes)
			)
		)
		(property "Value" "GND"
			(at 100.33 96.52 0)
			(effects
				(font
					(size 1.27 1.27)
					(thickness 0.15)
				)
			)
		)
		(property "Footprint" ""
			(at 109.22 100.33 0)
			(effects
				(font
					(size 1.27 1.27)
					(thickness 0.15)
				)
				(justify left bottom)
				(hide yes)
			)
		)
		(property "Datasheet" ""
			(at 109.22 105.41 0)
			(effects
				(font
					(size 1.27 1.27)
					(thickness 0.15)
				)
				(justify left bottom)
				(hide yes)
			)
		)
		(property "Description" ""
			(at 100.33 92.71 0)
			(effects
				(font
					(size 1.27 1.27)
				)
				(hide yes)
			)
		)
		(property "Author" "Antmicro"
			(at 109.22 100.33 0)
			(effects
				(font
					(size 1.27 1.27)
					(thickness 0.15)
				)
				(justify left bottom)
				(hide yes)
			)
		)
		(property "License" "Apache-2.0"
			(at 109.22 102.87 0)
			(effects
				(font
					(size 1.27 1.27)
					(thickness 0.15)
				)
				(justify left bottom)
				(hide yes)
			)
		)
		(pin "1"
		)
		(instances
			(project "jetson-agx-thor-baseboard"
				(path ""
					(reference "#PWR04")
					(unit 1)
				)
			)
		)
	)
	(symbol
		(lib_id "antmicroCapacitors0402:C_100n_0402")
		(at 113.03 209.55 270)
		(mirror x)
		(unit 1)
		(exclude_from_sim no)
		(in_bom yes)
		(on_board yes)
		(dnp no)
		(property "Reference" "C355"
			(at 114.935 205.74 90)
			(effects
				(font
					(size 1.27 1.27)
				)
				(justify left)
			)
		)
		(property "Value" "C_100n_0402"
			(at 102.87 189.23 0)
			(effects
				(font
					(size 1.27 1.27)
					(thickness 0.15)
				)
				(justify left bottom)
				(hide yes)
			)
		)
		(property "Footprint" "antmicro-footprints:C_0402_1005Metric"
			(at 100.33 189.23 0)
			(effects
				(font
					(size 1.27 1.27)
					(thickness 0.15)
				)
				(justify left bottom)
				(hide yes)
			)
		)
		(property "Datasheet" "https://www.murata.com/products/productdetail?partno=GRM155R61H104KE14%23"
			(at 97.79 189.23 0)
			(effects
				(font
					(size 1.27 1.27)
					(thickness 0.15)
				)
				(justify left bottom)
				(hide yes)
			)
		)
		(property "Description" "SMD Multilayer Ceramic Capacitor, 0.1 µF, 50 V, 0402 [1005 Metric], ± 10%, X5R, GRM Series"
			(at 113.03 209.55 0)
			(effects
				(font
					(size 1.27 1.27)
				)
				(hide yes)
			)
		)
		(property "Manufacturer" "Murata"
			(at 92.71 189.23 0)
			(effects
				(font
					(size 1.27 1.27)
					(thickness 0.15)
				)
				(justify left bottom)
				(hide yes)
			)
		)
		(property "MPN" "GRM155R61H104KE14D"
			(at 95.25 189.23 0)
			(effects
				(font
					(size 1.27 1.27)
					(thickness 0.15)
				)
				(justify left bottom)
				(hide yes)
			)
		)
		(property "Val" "100n"
			(at 114.935 208.28 90)
			(effects
				(font
					(size 1.27 1.27)
					(thickness 0.15)
				)
				(justify left)
			)
		)
		(property "License" "Apache-2.0"
			(at 90.17 189.23 0)
			(effects
				(font
					(size 1.27 1.27)
					(thickness 0.15)
				)
				(justify left bottom)
				(hide yes)
			)
		)
		(property "Author" "Antmicro"
			(at 87.63 189.23 0)
			(effects
				(font
					(size 1.27 1.27)
					(thickness 0.15)
				)
				(justify left bottom)
				(hide yes)
			)
		)
		(property "Voltage" "50V"
			(at 85.09 189.23 0)
			(effects
				(font
					(size 1.27 1.27)
				)
				(justify left bottom)
				(hide yes)
			)
		)
		(property "Dielectric" "X5R"
			(at 82.55 189.23 0)
			(effects
				(font
					(size 1.27 1.27)
				)
				(justify left bottom)
				(hide yes)
			)
		)
		(pin "1"
		)
		(pin "2"
		)
		(instances
			(project "jetson-agx-thor-baseboard"
				(path ""
					(reference "C355")
					(unit 1)
				)
			)
		)
	)
)
